FILE_TYPE = MACRO_DRAWING;
SET COLOR_WIRE YELLOW;
SET COLOR_PROP ORANGE;
SET COLOR_DOT WHITE;
SET COLOR_ARC YELLOW;
SET COLOR_BODY GREEN;
SET COLOR_NOTE PURPLE;
SET PROP_DISPLAY VALUE;
SET PAGE_NUMBER P101;
FORCEADD VCC_CORE..1
(-8700 3675);
FORCEPROP 3 LASTPIN (-8700 3625) SIG_NAME P3V3_AUX\g
J 0
(-8690 3635);
DISPLAY 0.659574 (-8690 3635);
PAINT MONO (-8690 3635);
DISPLAY INVISIBLE (-8690 3635);
FORCEPROP 1 LAST HDL_POWER P3V3_AUX
J 1
(-8700 3725);
DISPLAY 0.489362 (-8700 3725);
PAINT GREEN (-8700 3725);
FORCEPROP 2 LAST CDS_LIB mstr_symbols
J 0
(-8700 3675);
PAINT MONO (-8700 3675);
DISPLAY INVISIBLE (-8700 3675);
FORCEPROP 0 LAST VOLTAGE 3.3
J 0
(-8975 3825);
DISPLAY 1.021277 (-8975 3825);
PAINT SKYBLUE (-8975 3825);
DISPLAY INVISIBLE (-8975 3825);
FORCEPROP 2 LAST ROOM PVCCINFAON_CPU1_CTRL
J 0
(-8700 3775);
DISPLAY 0.808511 (-8700 3775);
PAINT RED (-8700 3775);
DISPLAY INVISIBLE (-8700 3775);
FORCEPROP 1 LAST PATH I1
J 0
(-8650 3700);
DISPLAY 0.872340 (-8650 3700);
PAINT AQUA (-8650 3700);
DISPLAY INVISIBLE (-8650 3700);
FORCEADD OFFPAGE..6
(-8475 3850);
FORCEPROP 2 LAST $XR0 41 
J 0
(-8754 3850);
DISPLAY 0.638298 (-8754 3850);
PAINT MONO (-8754 3850);
FORCEPROP 2 LAST CDS_LIB mstr_standard
J 0
(-8475 3850);
DISPLAY 0.723404 (-8475 3850);
PAINT MONO (-8475 3850);
DISPLAY INVISIBLE (-8475 3850);
FORCEPROP 1 LAST OFFPAGE TRUE
J 0
(-8150 3725);
DISPLAY 0.872340 (-8150 3725);
PAINT GREEN (-8150 3725);
DISPLAY INVISIBLE (-8150 3725);
FORCEPROP 1 LAST COMMENT_BODY TRUE
J 0
(-8375 3775);
DISPLAY 0.872340 (-8375 3775);
PAINT GREEN (-8375 3775);
DISPLAY INVISIBLE (-8375 3775);
FORCEPROP 2 LAST PATH I10
J 0
(-8750 3900);
DISPLAY 1.021277 (-8750 3900);
DISPLAY INVISIBLE (-8750 3900);
FORCEADD TAP..1
(-6175 4450);
FORCEPROP 3 LASTPIN (-6225 4450) SIG_NAME M_E_CPU1_SA_DQ<7>
J 0
(-6215 4460);
DISPLAY 0.659574 (-6215 4460);
PAINT MONO (-6215 4460);
DISPLAY INVISIBLE (-6215 4460);
FORCEPROP 1 LASTPIN (-6225 4450) BN 7
J 0
(-6237 4458);
DISPLAY 0.489362 (-6237 4458);
PAINT GREEN (-6237 4458);
FORCEPROP 2 LAST CDS_LIB mstr_standard
J 0
(-6175 4450);
DISPLAY 0.723404 (-6175 4450);
PAINT MONO (-6175 4450);
DISPLAY INVISIBLE (-6175 4450);
FORCEPROP 1 LAST BODY_TYPE PLUMBING
J 0
(-6175 4500);
DISPLAY 0.872340 (-6175 4500);
PAINT GREEN (-6175 4500);
DISPLAY INVISIBLE (-6175 4500);
FORCEPROP 1 LAST HDL_TAP TRUE
J 0
(-5850 4325);
DISPLAY 0.872340 (-5850 4325);
DISPLAY INVISIBLE (-5850 4325);
FORCEPROP 1 LAST PATH I100
J 0
(-6177 4450);
DISPLAY 0.872340 (-6177 4450);
PAINT GREEN (-6177 4450);
DISPLAY INVISIBLE (-6177 4450);
FORCEADD TAP..1
(-6175 4500);
FORCEPROP 3 LASTPIN (-6225 4500) SIG_NAME M_E_CPU1_SA_DQ<8>
J 0
(-6215 4510);
DISPLAY 0.659574 (-6215 4510);
PAINT MONO (-6215 4510);
DISPLAY INVISIBLE (-6215 4510);
FORCEPROP 1 LASTPIN (-6225 4500) BN 8
J 0
(-6237 4508);
DISPLAY 0.489362 (-6237 4508);
PAINT GREEN (-6237 4508);
FORCEPROP 2 LAST CDS_LIB mstr_standard
J 0
(-6175 4500);
DISPLAY 0.723404 (-6175 4500);
PAINT MONO (-6175 4500);
DISPLAY INVISIBLE (-6175 4500);
FORCEPROP 1 LAST BODY_TYPE PLUMBING
J 0
(-6175 4550);
DISPLAY 0.872340 (-6175 4550);
PAINT GREEN (-6175 4550);
DISPLAY INVISIBLE (-6175 4550);
FORCEPROP 1 LAST HDL_TAP TRUE
J 0
(-5850 4375);
DISPLAY 0.872340 (-5850 4375);
DISPLAY INVISIBLE (-5850 4375);
FORCEPROP 1 LAST PATH I101
J 0
(-6177 4500);
DISPLAY 0.872340 (-6177 4500);
PAINT GREEN (-6177 4500);
DISPLAY INVISIBLE (-6177 4500);
FORCEADD TAP..1
(-6175 4550);
FORCEPROP 3 LASTPIN (-6225 4550) SIG_NAME M_E_CPU1_SA_DQ<9>
J 0
(-6215 4560);
DISPLAY 0.659574 (-6215 4560);
PAINT MONO (-6215 4560);
DISPLAY INVISIBLE (-6215 4560);
FORCEPROP 1 LASTPIN (-6225 4550) BN 9
J 0
(-6237 4558);
DISPLAY 0.489362 (-6237 4558);
PAINT GREEN (-6237 4558);
FORCEPROP 2 LAST CDS_LIB mstr_standard
J 0
(-6175 4550);
DISPLAY 0.723404 (-6175 4550);
PAINT MONO (-6175 4550);
DISPLAY INVISIBLE (-6175 4550);
FORCEPROP 1 LAST BODY_TYPE PLUMBING
J 0
(-6175 4600);
DISPLAY 0.872340 (-6175 4600);
PAINT GREEN (-6175 4600);
DISPLAY INVISIBLE (-6175 4600);
FORCEPROP 1 LAST HDL_TAP TRUE
J 0
(-5850 4425);
DISPLAY 0.872340 (-5850 4425);
DISPLAY INVISIBLE (-5850 4425);
FORCEPROP 1 LAST PATH I102
J 0
(-6177 4550);
DISPLAY 0.872340 (-6177 4550);
PAINT GREEN (-6177 4550);
DISPLAY INVISIBLE (-6177 4550);
FORCEADD TAP..1
(-6175 4650);
FORCEPROP 3 LASTPIN (-6225 4650) SIG_NAME M_E_CPU1_SA_DQ<11>
J 0
(-6215 4660);
DISPLAY 0.659574 (-6215 4660);
PAINT MONO (-6215 4660);
DISPLAY INVISIBLE (-6215 4660);
FORCEPROP 1 LASTPIN (-6225 4650) BN 11
J 0
(-6237 4658);
DISPLAY 0.489362 (-6237 4658);
PAINT GREEN (-6237 4658);
FORCEPROP 2 LAST CDS_LIB mstr_standard
J 0
(-6175 4650);
DISPLAY 0.723404 (-6175 4650);
PAINT MONO (-6175 4650);
DISPLAY INVISIBLE (-6175 4650);
FORCEPROP 1 LAST BODY_TYPE PLUMBING
J 0
(-6175 4700);
DISPLAY 0.872340 (-6175 4700);
PAINT GREEN (-6175 4700);
DISPLAY INVISIBLE (-6175 4700);
FORCEPROP 1 LAST HDL_TAP TRUE
J 0
(-5850 4525);
DISPLAY 0.872340 (-5850 4525);
DISPLAY INVISIBLE (-5850 4525);
FORCEPROP 1 LAST PATH I103
J 0
(-6177 4650);
DISPLAY 0.872340 (-6177 4650);
PAINT GREEN (-6177 4650);
DISPLAY INVISIBLE (-6177 4650);
FORCEADD TAP..1
(-6175 4600);
FORCEPROP 3 LASTPIN (-6225 4600) SIG_NAME M_E_CPU1_SA_DQ<10>
J 0
(-6215 4610);
DISPLAY 0.659574 (-6215 4610);
PAINT MONO (-6215 4610);
DISPLAY INVISIBLE (-6215 4610);
FORCEPROP 1 LASTPIN (-6225 4600) BN 10
J 0
(-6237 4608);
DISPLAY 0.489362 (-6237 4608);
PAINT GREEN (-6237 4608);
FORCEPROP 2 LAST CDS_LIB mstr_standard
J 0
(-6175 4600);
DISPLAY 0.723404 (-6175 4600);
PAINT MONO (-6175 4600);
DISPLAY INVISIBLE (-6175 4600);
FORCEPROP 1 LAST BODY_TYPE PLUMBING
J 0
(-6175 4650);
DISPLAY 0.872340 (-6175 4650);
PAINT GREEN (-6175 4650);
DISPLAY INVISIBLE (-6175 4650);
FORCEPROP 1 LAST HDL_TAP TRUE
J 0
(-5850 4475);
DISPLAY 0.872340 (-5850 4475);
DISPLAY INVISIBLE (-5850 4475);
FORCEPROP 1 LAST PATH I104
J 0
(-6177 4600);
DISPLAY 0.872340 (-6177 4600);
PAINT GREEN (-6177 4600);
DISPLAY INVISIBLE (-6177 4600);
FORCEADD TAP..1
(-6175 4800);
FORCEPROP 3 LASTPIN (-6225 4800) SIG_NAME M_E_CPU1_SA_DQ<14>
J 0
(-6215 4810);
DISPLAY 0.659574 (-6215 4810);
PAINT MONO (-6215 4810);
DISPLAY INVISIBLE (-6215 4810);
FORCEPROP 1 LASTPIN (-6225 4800) BN 14
J 0
(-6237 4808);
DISPLAY 0.489362 (-6237 4808);
PAINT GREEN (-6237 4808);
FORCEPROP 2 LAST CDS_LIB mstr_standard
J 0
(-6175 4800);
DISPLAY 0.723404 (-6175 4800);
PAINT MONO (-6175 4800);
DISPLAY INVISIBLE (-6175 4800);
FORCEPROP 1 LAST BODY_TYPE PLUMBING
J 0
(-6175 4850);
DISPLAY 0.872340 (-6175 4850);
PAINT GREEN (-6175 4850);
DISPLAY INVISIBLE (-6175 4850);
FORCEPROP 1 LAST HDL_TAP TRUE
J 0
(-5850 4675);
DISPLAY 0.872340 (-5850 4675);
DISPLAY INVISIBLE (-5850 4675);
FORCEPROP 1 LAST PATH I105
J 0
(-6177 4800);
DISPLAY 0.872340 (-6177 4800);
PAINT GREEN (-6177 4800);
DISPLAY INVISIBLE (-6177 4800);
FORCEADD TAP..1
(-6175 4750);
FORCEPROP 3 LASTPIN (-6225 4750) SIG_NAME M_E_CPU1_SA_DQ<13>
J 0
(-6215 4760);
DISPLAY 0.659574 (-6215 4760);
PAINT MONO (-6215 4760);
DISPLAY INVISIBLE (-6215 4760);
FORCEPROP 1 LASTPIN (-6225 4750) BN 13
J 0
(-6237 4758);
DISPLAY 0.489362 (-6237 4758);
PAINT GREEN (-6237 4758);
FORCEPROP 2 LAST CDS_LIB mstr_standard
J 0
(-6175 4750);
DISPLAY 0.723404 (-6175 4750);
PAINT MONO (-6175 4750);
DISPLAY INVISIBLE (-6175 4750);
FORCEPROP 1 LAST BODY_TYPE PLUMBING
J 0
(-6175 4800);
DISPLAY 0.872340 (-6175 4800);
PAINT GREEN (-6175 4800);
DISPLAY INVISIBLE (-6175 4800);
FORCEPROP 1 LAST HDL_TAP TRUE
J 0
(-5850 4625);
DISPLAY 0.872340 (-5850 4625);
DISPLAY INVISIBLE (-5850 4625);
FORCEPROP 1 LAST PATH I106
J 0
(-6177 4750);
DISPLAY 0.872340 (-6177 4750);
PAINT GREEN (-6177 4750);
DISPLAY INVISIBLE (-6177 4750);
FORCEADD TAP..1
(-6175 4700);
FORCEPROP 3 LASTPIN (-6225 4700) SIG_NAME M_E_CPU1_SA_DQ<12>
J 0
(-6215 4710);
DISPLAY 0.659574 (-6215 4710);
PAINT MONO (-6215 4710);
DISPLAY INVISIBLE (-6215 4710);
FORCEPROP 1 LASTPIN (-6225 4700) BN 12
J 0
(-6237 4708);
DISPLAY 0.489362 (-6237 4708);
PAINT GREEN (-6237 4708);
FORCEPROP 2 LAST CDS_LIB mstr_standard
J 0
(-6175 4700);
DISPLAY 0.723404 (-6175 4700);
PAINT MONO (-6175 4700);
DISPLAY INVISIBLE (-6175 4700);
FORCEPROP 1 LAST BODY_TYPE PLUMBING
J 0
(-6175 4750);
DISPLAY 0.872340 (-6175 4750);
PAINT GREEN (-6175 4750);
DISPLAY INVISIBLE (-6175 4750);
FORCEPROP 1 LAST HDL_TAP TRUE
J 0
(-5850 4575);
DISPLAY 0.872340 (-5850 4575);
DISPLAY INVISIBLE (-5850 4575);
FORCEPROP 1 LAST PATH I107
J 0
(-6177 4700);
DISPLAY 0.872340 (-6177 4700);
PAINT GREEN (-6177 4700);
DISPLAY INVISIBLE (-6177 4700);
FORCEADD TAP..1
(-6175 4850);
FORCEPROP 3 LASTPIN (-6225 4850) SIG_NAME M_E_CPU1_SA_DQ<15>
J 0
(-6215 4860);
DISPLAY 0.659574 (-6215 4860);
PAINT MONO (-6215 4860);
DISPLAY INVISIBLE (-6215 4860);
FORCEPROP 1 LASTPIN (-6225 4850) BN 15
J 0
(-6237 4858);
DISPLAY 0.489362 (-6237 4858);
PAINT GREEN (-6237 4858);
FORCEPROP 2 LAST CDS_LIB mstr_standard
J 0
(-6175 4850);
DISPLAY 0.723404 (-6175 4850);
PAINT MONO (-6175 4850);
DISPLAY INVISIBLE (-6175 4850);
FORCEPROP 1 LAST BODY_TYPE PLUMBING
J 0
(-6175 4900);
DISPLAY 0.872340 (-6175 4900);
PAINT GREEN (-6175 4900);
DISPLAY INVISIBLE (-6175 4900);
FORCEPROP 1 LAST HDL_TAP TRUE
J 0
(-5850 4725);
DISPLAY 0.872340 (-5850 4725);
DISPLAY INVISIBLE (-5850 4725);
FORCEPROP 1 LAST PATH I108
J 0
(-6177 4850);
DISPLAY 0.872340 (-6177 4850);
PAINT GREEN (-6177 4850);
DISPLAY INVISIBLE (-6177 4850);
FORCEADD TAP..1
(-6175 4900);
FORCEPROP 3 LASTPIN (-6225 4900) SIG_NAME M_E_CPU1_SA_DQ<16>
J 0
(-6215 4910);
DISPLAY 0.659574 (-6215 4910);
PAINT MONO (-6215 4910);
DISPLAY INVISIBLE (-6215 4910);
FORCEPROP 1 LASTPIN (-6225 4900) BN 16
J 0
(-6237 4908);
DISPLAY 0.489362 (-6237 4908);
PAINT GREEN (-6237 4908);
FORCEPROP 2 LAST CDS_LIB mstr_standard
J 0
(-6175 4900);
DISPLAY 0.723404 (-6175 4900);
PAINT MONO (-6175 4900);
DISPLAY INVISIBLE (-6175 4900);
FORCEPROP 1 LAST BODY_TYPE PLUMBING
J 0
(-6175 4950);
DISPLAY 0.872340 (-6175 4950);
PAINT GREEN (-6175 4950);
DISPLAY INVISIBLE (-6175 4950);
FORCEPROP 1 LAST HDL_TAP TRUE
J 0
(-5850 4775);
DISPLAY 0.872340 (-5850 4775);
DISPLAY INVISIBLE (-5850 4775);
FORCEPROP 1 LAST PATH I109
J 0
(-6177 4900);
DISPLAY 0.872340 (-6177 4900);
PAINT GREEN (-6177 4900);
DISPLAY INVISIBLE (-6177 4900);
FORCEADD TAP..1
R 2
(-7875 3450);
FORCEPROP 3 LASTPIN (-7825 3450) SIG_NAME M_E_CPU1_SB_CB<0>
J 0
(-7815 3460);
DISPLAY 0.659574 (-7815 3460);
PAINT MONO (-7815 3460);
DISPLAY INVISIBLE (-7815 3460);
FORCEPROP 1 LASTPIN (-7825 3450) BN 0
J 2
(-7813 3458);
DISPLAY 0.489362 (-7813 3458);
PAINT GREEN (-7813 3458);
FORCEPROP 2 LAST CDS_LIB mstr_standard
J 0
(-7875 3450);
DISPLAY 0.723404 (-7875 3450);
PAINT MONO (-7875 3450);
DISPLAY INVISIBLE (-7875 3450);
FORCEPROP 1 LAST BODY_TYPE PLUMBING
J 2
(-7875 3500);
DISPLAY 0.872340 (-7875 3500);
PAINT GREEN (-7875 3500);
DISPLAY INVISIBLE (-7875 3500);
FORCEPROP 1 LAST HDL_TAP TRUE
J 2
(-8200 3325);
DISPLAY 0.872340 (-8200 3325);
DISPLAY INVISIBLE (-8200 3325);
FORCEPROP 1 LAST PATH I11
J 2
(-7873 3450);
DISPLAY 0.872340 (-7873 3450);
PAINT GREEN (-7873 3450);
DISPLAY INVISIBLE (-7873 3450);
FORCEADD TAP..1
(-6175 4950);
FORCEPROP 3 LASTPIN (-6225 4950) SIG_NAME M_E_CPU1_SA_DQ<17>
J 0
(-6215 4960);
DISPLAY 0.659574 (-6215 4960);
PAINT MONO (-6215 4960);
DISPLAY INVISIBLE (-6215 4960);
FORCEPROP 1 LASTPIN (-6225 4950) BN 17
J 0
(-6237 4958);
DISPLAY 0.489362 (-6237 4958);
PAINT GREEN (-6237 4958);
FORCEPROP 2 LAST CDS_LIB mstr_standard
J 0
(-6175 4950);
DISPLAY 0.723404 (-6175 4950);
PAINT MONO (-6175 4950);
DISPLAY INVISIBLE (-6175 4950);
FORCEPROP 1 LAST BODY_TYPE PLUMBING
J 0
(-6175 5000);
DISPLAY 0.872340 (-6175 5000);
PAINT GREEN (-6175 5000);
DISPLAY INVISIBLE (-6175 5000);
FORCEPROP 1 LAST HDL_TAP TRUE
J 0
(-5850 4825);
DISPLAY 0.872340 (-5850 4825);
DISPLAY INVISIBLE (-5850 4825);
FORCEPROP 1 LAST PATH I110
J 0
(-6177 4950);
DISPLAY 0.872340 (-6177 4950);
PAINT GREEN (-6177 4950);
DISPLAY INVISIBLE (-6177 4950);
FORCEADD TAP..1
(-6175 5000);
FORCEPROP 3 LASTPIN (-6225 5000) SIG_NAME M_E_CPU1_SA_DQ<18>
J 0
(-6215 5010);
DISPLAY 0.659574 (-6215 5010);
PAINT MONO (-6215 5010);
DISPLAY INVISIBLE (-6215 5010);
FORCEPROP 1 LASTPIN (-6225 5000) BN 18
J 0
(-6237 5008);
DISPLAY 0.489362 (-6237 5008);
PAINT GREEN (-6237 5008);
FORCEPROP 2 LAST CDS_LIB mstr_standard
J 0
(-6175 5000);
DISPLAY 0.723404 (-6175 5000);
PAINT MONO (-6175 5000);
DISPLAY INVISIBLE (-6175 5000);
FORCEPROP 1 LAST BODY_TYPE PLUMBING
J 0
(-6175 5050);
DISPLAY 0.872340 (-6175 5050);
PAINT GREEN (-6175 5050);
DISPLAY INVISIBLE (-6175 5050);
FORCEPROP 1 LAST HDL_TAP TRUE
J 0
(-5850 4875);
DISPLAY 0.872340 (-5850 4875);
DISPLAY INVISIBLE (-5850 4875);
FORCEPROP 1 LAST PATH I111
J 0
(-6177 5000);
DISPLAY 0.872340 (-6177 5000);
PAINT GREEN (-6177 5000);
DISPLAY INVISIBLE (-6177 5000);
FORCEADD TAP..1
(-6175 5050);
FORCEPROP 3 LASTPIN (-6225 5050) SIG_NAME M_E_CPU1_SA_DQ<19>
J 0
(-6215 5060);
DISPLAY 0.659574 (-6215 5060);
PAINT MONO (-6215 5060);
DISPLAY INVISIBLE (-6215 5060);
FORCEPROP 1 LASTPIN (-6225 5050) BN 19
J 0
(-6237 5058);
DISPLAY 0.489362 (-6237 5058);
PAINT GREEN (-6237 5058);
FORCEPROP 2 LAST CDS_LIB mstr_standard
J 0
(-6175 5050);
DISPLAY 0.723404 (-6175 5050);
PAINT MONO (-6175 5050);
DISPLAY INVISIBLE (-6175 5050);
FORCEPROP 1 LAST BODY_TYPE PLUMBING
J 0
(-6175 5100);
DISPLAY 0.872340 (-6175 5100);
PAINT GREEN (-6175 5100);
DISPLAY INVISIBLE (-6175 5100);
FORCEPROP 1 LAST HDL_TAP TRUE
J 0
(-5850 4925);
DISPLAY 0.872340 (-5850 4925);
DISPLAY INVISIBLE (-5850 4925);
FORCEPROP 1 LAST PATH I112
J 0
(-6177 5050);
DISPLAY 0.872340 (-6177 5050);
PAINT GREEN (-6177 5050);
DISPLAY INVISIBLE (-6177 5050);
FORCEADD TAP..1
(-6175 5100);
FORCEPROP 3 LASTPIN (-6225 5100) SIG_NAME M_E_CPU1_SA_DQ<20>
J 0
(-6215 5110);
DISPLAY 0.659574 (-6215 5110);
PAINT MONO (-6215 5110);
DISPLAY INVISIBLE (-6215 5110);
FORCEPROP 1 LASTPIN (-6225 5100) BN 20
J 0
(-6237 5108);
DISPLAY 0.489362 (-6237 5108);
PAINT GREEN (-6237 5108);
FORCEPROP 2 LAST CDS_LIB mstr_standard
J 0
(-6175 5100);
DISPLAY 0.723404 (-6175 5100);
PAINT MONO (-6175 5100);
DISPLAY INVISIBLE (-6175 5100);
FORCEPROP 1 LAST BODY_TYPE PLUMBING
J 0
(-6175 5150);
DISPLAY 0.872340 (-6175 5150);
PAINT GREEN (-6175 5150);
DISPLAY INVISIBLE (-6175 5150);
FORCEPROP 1 LAST HDL_TAP TRUE
J 0
(-5850 4975);
DISPLAY 0.872340 (-5850 4975);
DISPLAY INVISIBLE (-5850 4975);
FORCEPROP 1 LAST PATH I113
J 0
(-6177 5100);
DISPLAY 0.872340 (-6177 5100);
PAINT GREEN (-6177 5100);
DISPLAY INVISIBLE (-6177 5100);
FORCEADD TAP..1
(-6175 5150);
FORCEPROP 3 LASTPIN (-6225 5150) SIG_NAME M_E_CPU1_SA_DQ<21>
J 0
(-6215 5160);
DISPLAY 0.659574 (-6215 5160);
PAINT MONO (-6215 5160);
DISPLAY INVISIBLE (-6215 5160);
FORCEPROP 1 LASTPIN (-6225 5150) BN 21
J 0
(-6237 5158);
DISPLAY 0.489362 (-6237 5158);
PAINT GREEN (-6237 5158);
FORCEPROP 2 LAST CDS_LIB mstr_standard
J 0
(-6175 5150);
DISPLAY 0.723404 (-6175 5150);
PAINT MONO (-6175 5150);
DISPLAY INVISIBLE (-6175 5150);
FORCEPROP 1 LAST BODY_TYPE PLUMBING
J 0
(-6175 5200);
DISPLAY 0.872340 (-6175 5200);
PAINT GREEN (-6175 5200);
DISPLAY INVISIBLE (-6175 5200);
FORCEPROP 1 LAST HDL_TAP TRUE
J 0
(-5850 5025);
DISPLAY 0.872340 (-5850 5025);
DISPLAY INVISIBLE (-5850 5025);
FORCEPROP 1 LAST PATH I114
J 0
(-6177 5150);
DISPLAY 0.872340 (-6177 5150);
PAINT GREEN (-6177 5150);
DISPLAY INVISIBLE (-6177 5150);
FORCEADD TAP..1
(-6175 5250);
FORCEPROP 3 LASTPIN (-6225 5250) SIG_NAME M_E_CPU1_SA_DQ<23>
J 0
(-6215 5260);
DISPLAY 0.659574 (-6215 5260);
PAINT MONO (-6215 5260);
DISPLAY INVISIBLE (-6215 5260);
FORCEPROP 1 LASTPIN (-6225 5250) BN 23
J 0
(-6237 5258);
DISPLAY 0.489362 (-6237 5258);
PAINT GREEN (-6237 5258);
FORCEPROP 2 LAST CDS_LIB mstr_standard
J 0
(-6175 5250);
DISPLAY 0.723404 (-6175 5250);
PAINT MONO (-6175 5250);
DISPLAY INVISIBLE (-6175 5250);
FORCEPROP 1 LAST BODY_TYPE PLUMBING
J 0
(-6175 5300);
DISPLAY 0.872340 (-6175 5300);
PAINT GREEN (-6175 5300);
DISPLAY INVISIBLE (-6175 5300);
FORCEPROP 1 LAST HDL_TAP TRUE
J 0
(-5850 5125);
DISPLAY 0.872340 (-5850 5125);
DISPLAY INVISIBLE (-5850 5125);
FORCEPROP 1 LAST PATH I115
J 0
(-6177 5250);
DISPLAY 0.872340 (-6177 5250);
PAINT GREEN (-6177 5250);
DISPLAY INVISIBLE (-6177 5250);
FORCEADD TAP..1
(-6175 5200);
FORCEPROP 3 LASTPIN (-6225 5200) SIG_NAME M_E_CPU1_SA_DQ<22>
J 0
(-6215 5210);
DISPLAY 0.659574 (-6215 5210);
PAINT MONO (-6215 5210);
DISPLAY INVISIBLE (-6215 5210);
FORCEPROP 1 LASTPIN (-6225 5200) BN 22
J 0
(-6237 5208);
DISPLAY 0.489362 (-6237 5208);
PAINT GREEN (-6237 5208);
FORCEPROP 2 LAST CDS_LIB mstr_standard
J 0
(-6175 5200);
DISPLAY 0.723404 (-6175 5200);
PAINT MONO (-6175 5200);
DISPLAY INVISIBLE (-6175 5200);
FORCEPROP 1 LAST BODY_TYPE PLUMBING
J 0
(-6175 5250);
DISPLAY 0.872340 (-6175 5250);
PAINT GREEN (-6175 5250);
DISPLAY INVISIBLE (-6175 5250);
FORCEPROP 1 LAST HDL_TAP TRUE
J 0
(-5850 5075);
DISPLAY 0.872340 (-5850 5075);
DISPLAY INVISIBLE (-5850 5075);
FORCEPROP 1 LAST PATH I116
J 0
(-6177 5200);
DISPLAY 0.872340 (-6177 5200);
PAINT GREEN (-6177 5200);
DISPLAY INVISIBLE (-6177 5200);
FORCEADD TAP..1
(-6175 5300);
FORCEPROP 3 LASTPIN (-6225 5300) SIG_NAME M_E_CPU1_SA_DQ<24>
J 0
(-6215 5310);
DISPLAY 0.659574 (-6215 5310);
PAINT MONO (-6215 5310);
DISPLAY INVISIBLE (-6215 5310);
FORCEPROP 1 LASTPIN (-6225 5300) BN 24
J 0
(-6237 5308);
DISPLAY 0.489362 (-6237 5308);
PAINT GREEN (-6237 5308);
FORCEPROP 2 LAST CDS_LIB mstr_standard
J 0
(-6175 5300);
DISPLAY 0.723404 (-6175 5300);
PAINT MONO (-6175 5300);
DISPLAY INVISIBLE (-6175 5300);
FORCEPROP 1 LAST BODY_TYPE PLUMBING
J 0
(-6175 5350);
DISPLAY 0.872340 (-6175 5350);
PAINT GREEN (-6175 5350);
DISPLAY INVISIBLE (-6175 5350);
FORCEPROP 1 LAST HDL_TAP TRUE
J 0
(-5850 5175);
DISPLAY 0.872340 (-5850 5175);
DISPLAY INVISIBLE (-5850 5175);
FORCEPROP 1 LAST PATH I117
J 0
(-6177 5300);
DISPLAY 0.872340 (-6177 5300);
PAINT GREEN (-6177 5300);
DISPLAY INVISIBLE (-6177 5300);
FORCEADD TAP..1
(-6175 5450);
FORCEPROP 3 LASTPIN (-6225 5450) SIG_NAME M_E_CPU1_SA_DQ<27>
J 0
(-6215 5460);
DISPLAY 0.659574 (-6215 5460);
PAINT MONO (-6215 5460);
DISPLAY INVISIBLE (-6215 5460);
FORCEPROP 1 LASTPIN (-6225 5450) BN 27
J 0
(-6237 5458);
DISPLAY 0.489362 (-6237 5458);
PAINT GREEN (-6237 5458);
FORCEPROP 2 LAST CDS_LIB mstr_standard
J 0
(-6175 5450);
DISPLAY 0.723404 (-6175 5450);
PAINT MONO (-6175 5450);
DISPLAY INVISIBLE (-6175 5450);
FORCEPROP 1 LAST BODY_TYPE PLUMBING
J 0
(-6175 5500);
DISPLAY 0.872340 (-6175 5500);
PAINT GREEN (-6175 5500);
DISPLAY INVISIBLE (-6175 5500);
FORCEPROP 1 LAST HDL_TAP TRUE
J 0
(-5850 5325);
DISPLAY 0.872340 (-5850 5325);
DISPLAY INVISIBLE (-5850 5325);
FORCEPROP 1 LAST PATH I118
J 0
(-6177 5450);
DISPLAY 0.872340 (-6177 5450);
PAINT GREEN (-6177 5450);
DISPLAY INVISIBLE (-6177 5450);
FORCEADD TAP..1
(-6175 5400);
FORCEPROP 3 LASTPIN (-6225 5400) SIG_NAME M_E_CPU1_SA_DQ<26>
J 0
(-6215 5410);
DISPLAY 0.659574 (-6215 5410);
PAINT MONO (-6215 5410);
DISPLAY INVISIBLE (-6215 5410);
FORCEPROP 1 LASTPIN (-6225 5400) BN 26
J 0
(-6237 5408);
DISPLAY 0.489362 (-6237 5408);
PAINT GREEN (-6237 5408);
FORCEPROP 2 LAST CDS_LIB mstr_standard
J 0
(-6175 5400);
DISPLAY 0.723404 (-6175 5400);
PAINT MONO (-6175 5400);
DISPLAY INVISIBLE (-6175 5400);
FORCEPROP 1 LAST BODY_TYPE PLUMBING
J 0
(-6175 5450);
DISPLAY 0.872340 (-6175 5450);
PAINT GREEN (-6175 5450);
DISPLAY INVISIBLE (-6175 5450);
FORCEPROP 1 LAST HDL_TAP TRUE
J 0
(-5850 5275);
DISPLAY 0.872340 (-5850 5275);
DISPLAY INVISIBLE (-5850 5275);
FORCEPROP 1 LAST PATH I119
J 0
(-6177 5400);
DISPLAY 0.872340 (-6177 5400);
PAINT GREEN (-6177 5400);
DISPLAY INVISIBLE (-6177 5400);
FORCEADD TAP..1
R 2
(-7875 3500);
FORCEPROP 3 LASTPIN (-7825 3500) SIG_NAME M_E_CPU1_SB_CB<1>
J 0
(-7815 3510);
DISPLAY 0.659574 (-7815 3510);
PAINT MONO (-7815 3510);
DISPLAY INVISIBLE (-7815 3510);
FORCEPROP 1 LASTPIN (-7825 3500) BN 1
J 2
(-7813 3508);
DISPLAY 0.489362 (-7813 3508);
PAINT GREEN (-7813 3508);
FORCEPROP 2 LAST CDS_LIB mstr_standard
J 0
(-7875 3500);
DISPLAY 0.723404 (-7875 3500);
PAINT MONO (-7875 3500);
DISPLAY INVISIBLE (-7875 3500);
FORCEPROP 1 LAST BODY_TYPE PLUMBING
J 2
(-7875 3550);
DISPLAY 0.872340 (-7875 3550);
PAINT GREEN (-7875 3550);
DISPLAY INVISIBLE (-7875 3550);
FORCEPROP 1 LAST HDL_TAP TRUE
J 2
(-8200 3375);
DISPLAY 0.872340 (-8200 3375);
DISPLAY INVISIBLE (-8200 3375);
FORCEPROP 1 LAST PATH I12
J 2
(-7873 3500);
DISPLAY 0.872340 (-7873 3500);
PAINT GREEN (-7873 3500);
DISPLAY INVISIBLE (-7873 3500);
FORCEADD TAP..1
(-6175 5350);
FORCEPROP 3 LASTPIN (-6225 5350) SIG_NAME M_E_CPU1_SA_DQ<25>
J 0
(-6215 5360);
DISPLAY 0.659574 (-6215 5360);
PAINT MONO (-6215 5360);
DISPLAY INVISIBLE (-6215 5360);
FORCEPROP 1 LASTPIN (-6225 5350) BN 25
J 0
(-6237 5358);
DISPLAY 0.489362 (-6237 5358);
PAINT GREEN (-6237 5358);
FORCEPROP 2 LAST CDS_LIB mstr_standard
J 0
(-6175 5350);
DISPLAY 0.723404 (-6175 5350);
PAINT MONO (-6175 5350);
DISPLAY INVISIBLE (-6175 5350);
FORCEPROP 1 LAST BODY_TYPE PLUMBING
J 0
(-6175 5400);
DISPLAY 0.872340 (-6175 5400);
PAINT GREEN (-6175 5400);
DISPLAY INVISIBLE (-6175 5400);
FORCEPROP 1 LAST HDL_TAP TRUE
J 0
(-5850 5225);
DISPLAY 0.872340 (-5850 5225);
DISPLAY INVISIBLE (-5850 5225);
FORCEPROP 1 LAST PATH I120
J 0
(-6177 5350);
DISPLAY 0.872340 (-6177 5350);
PAINT GREEN (-6177 5350);
DISPLAY INVISIBLE (-6177 5350);
FORCEADD TAP..1
(-6175 5500);
FORCEPROP 3 LASTPIN (-6225 5500) SIG_NAME M_E_CPU1_SA_DQ<28>
J 0
(-6215 5510);
DISPLAY 0.659574 (-6215 5510);
PAINT MONO (-6215 5510);
DISPLAY INVISIBLE (-6215 5510);
FORCEPROP 1 LASTPIN (-6225 5500) BN 28
J 0
(-6237 5508);
DISPLAY 0.489362 (-6237 5508);
PAINT GREEN (-6237 5508);
FORCEPROP 2 LAST CDS_LIB mstr_standard
J 0
(-6175 5500);
DISPLAY 0.723404 (-6175 5500);
PAINT MONO (-6175 5500);
DISPLAY INVISIBLE (-6175 5500);
FORCEPROP 1 LAST BODY_TYPE PLUMBING
J 0
(-6175 5550);
DISPLAY 0.872340 (-6175 5550);
PAINT GREEN (-6175 5550);
DISPLAY INVISIBLE (-6175 5550);
FORCEPROP 1 LAST HDL_TAP TRUE
J 0
(-5850 5375);
DISPLAY 0.872340 (-5850 5375);
DISPLAY INVISIBLE (-5850 5375);
FORCEPROP 1 LAST PATH I121
J 0
(-6177 5500);
DISPLAY 0.872340 (-6177 5500);
PAINT GREEN (-6177 5500);
DISPLAY INVISIBLE (-6177 5500);
FORCEADD TAP..1
(-6175 5550);
FORCEPROP 3 LASTPIN (-6225 5550) SIG_NAME M_E_CPU1_SA_DQ<29>
J 0
(-6215 5560);
DISPLAY 0.659574 (-6215 5560);
PAINT MONO (-6215 5560);
DISPLAY INVISIBLE (-6215 5560);
FORCEPROP 1 LASTPIN (-6225 5550) BN 29
J 0
(-6237 5558);
DISPLAY 0.489362 (-6237 5558);
PAINT GREEN (-6237 5558);
FORCEPROP 2 LAST CDS_LIB mstr_standard
J 0
(-6175 5550);
DISPLAY 0.723404 (-6175 5550);
PAINT MONO (-6175 5550);
DISPLAY INVISIBLE (-6175 5550);
FORCEPROP 1 LAST BODY_TYPE PLUMBING
J 0
(-6175 5600);
DISPLAY 0.872340 (-6175 5600);
PAINT GREEN (-6175 5600);
DISPLAY INVISIBLE (-6175 5600);
FORCEPROP 1 LAST HDL_TAP TRUE
J 0
(-5850 5425);
DISPLAY 0.872340 (-5850 5425);
DISPLAY INVISIBLE (-5850 5425);
FORCEPROP 1 LAST PATH I122
J 0
(-6177 5550);
DISPLAY 0.872340 (-6177 5550);
PAINT GREEN (-6177 5550);
DISPLAY INVISIBLE (-6177 5550);
FORCEADD TAP..1
(-6175 5650);
FORCEPROP 3 LASTPIN (-6225 5650) SIG_NAME M_E_CPU1_SA_DQ<31>
J 0
(-6215 5660);
DISPLAY 0.659574 (-6215 5660);
PAINT MONO (-6215 5660);
DISPLAY INVISIBLE (-6215 5660);
FORCEPROP 1 LASTPIN (-6225 5650) BN 31
J 0
(-6237 5658);
DISPLAY 0.489362 (-6237 5658);
PAINT GREEN (-6237 5658);
FORCEPROP 2 LAST CDS_LIB mstr_standard
J 0
(-6175 5650);
DISPLAY 0.723404 (-6175 5650);
PAINT MONO (-6175 5650);
DISPLAY INVISIBLE (-6175 5650);
FORCEPROP 1 LAST BODY_TYPE PLUMBING
J 0
(-6175 5700);
DISPLAY 0.872340 (-6175 5700);
PAINT GREEN (-6175 5700);
DISPLAY INVISIBLE (-6175 5700);
FORCEPROP 1 LAST HDL_TAP TRUE
J 0
(-5850 5525);
DISPLAY 0.872340 (-5850 5525);
DISPLAY INVISIBLE (-5850 5525);
FORCEPROP 1 LAST PATH I123
J 0
(-6177 5650);
DISPLAY 0.872340 (-6177 5650);
PAINT GREEN (-6177 5650);
DISPLAY INVISIBLE (-6177 5650);
FORCEADD TAP..1
(-6175 5600);
FORCEPROP 3 LASTPIN (-6225 5600) SIG_NAME M_E_CPU1_SA_DQ<30>
J 0
(-6215 5610);
DISPLAY 0.659574 (-6215 5610);
PAINT MONO (-6215 5610);
DISPLAY INVISIBLE (-6215 5610);
FORCEPROP 1 LASTPIN (-6225 5600) BN 30
J 0
(-6237 5608);
DISPLAY 0.489362 (-6237 5608);
PAINT GREEN (-6237 5608);
FORCEPROP 2 LAST CDS_LIB mstr_standard
J 0
(-6175 5600);
DISPLAY 0.723404 (-6175 5600);
PAINT MONO (-6175 5600);
DISPLAY INVISIBLE (-6175 5600);
FORCEPROP 1 LAST BODY_TYPE PLUMBING
J 0
(-6175 5650);
DISPLAY 0.872340 (-6175 5650);
PAINT GREEN (-6175 5650);
DISPLAY INVISIBLE (-6175 5650);
FORCEPROP 1 LAST HDL_TAP TRUE
J 0
(-5850 5475);
DISPLAY 0.872340 (-5850 5475);
DISPLAY INVISIBLE (-5850 5475);
FORCEPROP 1 LAST PATH I124
J 0
(-6177 5600);
DISPLAY 0.872340 (-6177 5600);
PAINT GREEN (-6177 5600);
DISPLAY INVISIBLE (-6177 5600);
FORCEADD OFFPAGE..3
(-5500 5700);
FORCEPROP 2 LAST $XR0 41 
J 0
(-5286 5700);
DISPLAY 0.638298 (-5286 5700);
PAINT MONO (-5286 5700);
FORCEPROP 2 LAST CDS_LIB mstr_standard
J 0
(-5500 5700);
DISPLAY 0.723404 (-5500 5700);
PAINT MONO (-5500 5700);
DISPLAY INVISIBLE (-5500 5700);
FORCEPROP 1 LAST OFFPAGE TRUE
J 0
(-5175 5575);
DISPLAY 0.872340 (-5175 5575);
PAINT GREEN (-5175 5575);
DISPLAY INVISIBLE (-5175 5575);
FORCEPROP 1 LAST COMMENT_BODY TRUE
J 0
(-5550 5600);
DISPLAY 0.872340 (-5550 5600);
PAINT GREEN (-5550 5600);
DISPLAY INVISIBLE (-5550 5600);
FORCEPROP 2 LAST PATH I125
J 0
(-5275 5750);
DISPLAY 1.021277 (-5275 5750);
DISPLAY INVISIBLE (-5275 5750);
FORCEADD GND..1
(-6575 1250);
FORCEPROP 3 LASTPIN (-6575 1300) SIG_NAME GND\g
J 0
(-6565 1310);
DISPLAY 0.659574 (-6565 1310);
PAINT MONO (-6565 1310);
DISPLAY INVISIBLE (-6565 1310);
FORCEPROP 2 LAST BOM_COST MEM
J 0
(-6675 1325);
DISPLAY 0.808511 (-6675 1325);
DISPLAY INVISIBLE (-6675 1325);
FORCEPROP 1 LAST SIZE 1B
J 0
(-6500 1200);
DISPLAY 0.851064 (-6500 1200);
PAINT GREEN (-6500 1200);
DISPLAY INVISIBLE (-6500 1200);
FORCEPROP 2 LAST CDS_LIB mstr_symbols
J 0
(-6575 1250);
DISPLAY 0.808511 (-6575 1250);
DISPLAY INVISIBLE (-6575 1250);
FORCEPROP 1 LAST VOLTAGE 0.0
J 0
(-6620 1207);
DISPLAY 0.723404 (-6620 1207);
PAINT SKYBLUE (-6620 1207);
DISPLAY INVISIBLE (-6620 1207);
FORCEPROP 1 LAST BODY_TYPE PLUMBING
J 0
(-6620 1207);
DISPLAY 0.340426 (-6620 1207);
PAINT GREEN (-6620 1207);
DISPLAY INVISIBLE (-6620 1207);
FORCEPROP 1 LAST HDL_POWER GND
J 0
(-6575 1400);
DISPLAY 0.851064 (-6575 1400);
PAINT GREEN (-6575 1400);
DISPLAY INVISIBLE (-6575 1400);
FORCEPROP 1 LAST PATH I126
J 0
(-6500 1250);
DISPLAY 0.872340 (-6500 1250);
PAINT AQUA (-6500 1250);
DISPLAY INVISIBLE (-6500 1250);
FORCEADD Q_RES..2
(-6575 1475);
FORCEPROP 1 LAST LOCATION R6
J 0
(-6530 1600);
DISPLAY 0.489362 (-6530 1600);
PAINT SKYBLUE (-6530 1600);
FORCEPROP 2 LAST SEC 1
J 0
(-6525 1700);
DISPLAY 0.808511 (-6525 1700);
PAINT MONO (-6525 1700);
DISPLAY INVISIBLE (-6525 1700);
FORCEPROP 1 LASTPIN (-6575 1575) $PN 1
J 0
(-6570 1537);
DISPLAY 0.489362 (-6570 1537);
PAINT WHITE (-6570 1537);
FORCEPROP 1 LASTPIN (-6575 1375) $PN 2
J 0
(-6570 1385);
DISPLAY 0.489362 (-6570 1385);
PAINT WHITE (-6570 1385);
FORCEPROP 0 LASTPIN (-6575 1575) XNET_PINS 3
R 1
J 0
(-6585 1585);
DISPLAY 0.808511 (-6585 1585);
PAINT MONO (-6585 1585);
DISPLAY INVISIBLE (-6585 1585);
FORCEPROP 0 LASTPIN (-6575 1375) XNET_PINS 2
R 1
J 2
(-6585 1365);
DISPLAY 0.808511 (-6585 1365);
PAINT MONO (-6585 1365);
DISPLAY INVISIBLE (-6585 1365);
FORCEPROP 1 LAST PACK_TYPE 0402LF
J 0
(-6535 1300);
DISPLAY 0.489362 (-6535 1300);
PAINT SKYBLUE (-6535 1300);
FORCEPROP 1 LAST VALUE 54.9K
J 0
(-6530 1550);
DISPLAY 0.489362 (-6530 1550);
PAINT SKYBLUE (-6530 1550);
FORCEPROP 1 LAST TOLERANCE 1%
J 0
(-6530 1500);
DISPLAY 0.489362 (-6530 1500);
PAINT SKYBLUE (-6530 1500);
FORCEPROP 1 LAST MATERIAL CHIP
J 0
(-6535 1400);
DISPLAY 0.489362 (-6535 1400);
PAINT SKYBLUE (-6535 1400);
FORCEPROP 1 LAST WATTAGE 1/16W
J 0
(-6535 1450);
DISPLAY 0.489362 (-6535 1450);
PAINT SKYBLUE (-6535 1450);
FORCEPROP 2 LAST SEC_TYPE 0402LF
J 0
(-6525 1700);
DISPLAY 0.808511 (-6525 1700);
PAINT MONO (-6525 1700);
DISPLAY INVISIBLE (-6525 1700);
FORCEPROP 2 LAST CDS_LIB pure_quanta
J 0
(-6575 1475);
DISPLAY INVISIBLE (-6575 1475);
FORCEPROP 2 LAST BOM_COST MEM
J 0
(-6525 1650);
DISPLAY 0.808511 (-6525 1650);
DISPLAY INVISIBLE (-6525 1650);
FORCEPROP 1 LAST PATH I127
J 0
(-6525 1650);
DISPLAY 0.978723 (-6525 1650);
PAINT WHITE (-6525 1650);
DISPLAY INVISIBLE (-6525 1650);
FORCEPROP 1 LAST PART_NUMBER CS35492FB03
J 0
(-6535 1350);
DISPLAY 0.489362 (-6535 1350);
PAINT SKYBLUE (-6535 1350);
DISPLAY INVISIBLE (-6535 1350);
FORCEADD OFFPAGE..5
(-7350 1650);
FORCEPROP 2 LAST $XR0 102 
J 0
(-7605 1650);
DISPLAY 0.638298 (-7605 1650);
PAINT MONO (-7605 1650);
FORCEPROP 2 LAST CDS_LIB mstr_standard
J 0
(-7350 1650);
DISPLAY 0.808511 (-7350 1650);
DISPLAY INVISIBLE (-7350 1650);
FORCEPROP 2 LAST BOM_COST MEM
J 0
(-7425 1725);
DISPLAY 0.808511 (-7425 1725);
DISPLAY INVISIBLE (-7425 1725);
FORCEPROP 1 LAST OFFPAGE TRUE
J 0
(-7025 1525);
DISPLAY 0.872340 (-7025 1525);
PAINT GREEN (-7025 1525);
DISPLAY INVISIBLE (-7025 1525);
FORCEPROP 1 LAST COMMENT_BODY TRUE
J 0
(-7250 1575);
DISPLAY 0.872340 (-7250 1575);
PAINT GREEN (-7250 1575);
DISPLAY INVISIBLE (-7250 1575);
FORCEPROP 2 LAST PATH I128
J 0
(-7600 1700);
DISPLAY 1.021277 (-7600 1700);
DISPLAY INVISIBLE (-7600 1700);
FORCEADD TAP..1
R 2
(-7875 3550);
FORCEPROP 3 LASTPIN (-7825 3550) SIG_NAME M_E_CPU1_SB_CB<2>
J 0
(-7815 3560);
DISPLAY 0.659574 (-7815 3560);
PAINT MONO (-7815 3560);
DISPLAY INVISIBLE (-7815 3560);
FORCEPROP 1 LASTPIN (-7825 3550) BN 2
J 2
(-7813 3558);
DISPLAY 0.489362 (-7813 3558);
PAINT GREEN (-7813 3558);
FORCEPROP 2 LAST CDS_LIB mstr_standard
J 0
(-7875 3550);
DISPLAY 0.723404 (-7875 3550);
PAINT MONO (-7875 3550);
DISPLAY INVISIBLE (-7875 3550);
FORCEPROP 1 LAST BODY_TYPE PLUMBING
J 2
(-7875 3600);
DISPLAY 0.872340 (-7875 3600);
PAINT GREEN (-7875 3600);
DISPLAY INVISIBLE (-7875 3600);
FORCEPROP 1 LAST HDL_TAP TRUE
J 2
(-8200 3425);
DISPLAY 0.872340 (-8200 3425);
DISPLAY INVISIBLE (-8200 3425);
FORCEPROP 1 LAST PATH I13
J 2
(-7873 3550);
DISPLAY 0.872340 (-7873 3550);
PAINT GREEN (-7873 3550);
DISPLAY INVISIBLE (-7873 3550);
FORCEADD TAP..1
R 2
(-7875 3600);
FORCEPROP 3 LASTPIN (-7825 3600) SIG_NAME M_E_CPU1_SB_CB<3>
J 0
(-7815 3610);
DISPLAY 0.659574 (-7815 3610);
PAINT MONO (-7815 3610);
DISPLAY INVISIBLE (-7815 3610);
FORCEPROP 1 LASTPIN (-7825 3600) BN 3
J 2
(-7813 3608);
DISPLAY 0.489362 (-7813 3608);
PAINT GREEN (-7813 3608);
FORCEPROP 2 LAST CDS_LIB mstr_standard
J 0
(-7875 3600);
DISPLAY 0.723404 (-7875 3600);
PAINT MONO (-7875 3600);
DISPLAY INVISIBLE (-7875 3600);
FORCEPROP 1 LAST BODY_TYPE PLUMBING
J 2
(-7875 3650);
DISPLAY 0.872340 (-7875 3650);
PAINT GREEN (-7875 3650);
DISPLAY INVISIBLE (-7875 3650);
FORCEPROP 1 LAST HDL_TAP TRUE
J 2
(-8200 3475);
DISPLAY 0.872340 (-8200 3475);
DISPLAY INVISIBLE (-8200 3475);
FORCEPROP 1 LAST PATH I14
J 2
(-7873 3600);
DISPLAY 0.872340 (-7873 3600);
PAINT GREEN (-7873 3600);
DISPLAY INVISIBLE (-7873 3600);
FORCEADD GND..1
(-2175 2250);
FORCEPROP 3 LASTPIN (-2175 2300) SIG_NAME GND\g
J 0
(-2165 2310);
DISPLAY 0.659574 (-2165 2310);
PAINT MONO (-2165 2310);
DISPLAY INVISIBLE (-2165 2310);
FORCEPROP 2 LAST CDS_LIB mstr_symbols
J 0
(-2175 2250);
DISPLAY 0.723404 (-2175 2250);
DISPLAY INVISIBLE (-2175 2250);
FORCEPROP 1 LAST SIZE 1B
J 0
(-2100 2200);
DISPLAY 0.851064 (-2100 2200);
PAINT GREEN (-2100 2200);
DISPLAY INVISIBLE (-2100 2200);
FORCEPROP 1 LAST VOLTAGE 0.0
J 0
(-2220 2207);
DISPLAY 0.723404 (-2220 2207);
PAINT SKYBLUE (-2220 2207);
DISPLAY INVISIBLE (-2220 2207);
FORCEPROP 1 LAST BODY_TYPE PLUMBING
J 0
(-2220 2207);
DISPLAY 0.340426 (-2220 2207);
PAINT GREEN (-2220 2207);
DISPLAY INVISIBLE (-2220 2207);
FORCEPROP 1 LAST HDL_POWER GND
J 0
(-2175 2400);
DISPLAY 0.851064 (-2175 2400);
PAINT GREEN (-2175 2400);
DISPLAY INVISIBLE (-2175 2400);
FORCEPROP 1 LAST PATH I140
J 0
(-2100 2250);
DISPLAY 0.872340 (-2100 2250);
PAINT AQUA (-2100 2250);
DISPLAY INVISIBLE (-2100 2250);
FORCEADD GND..1
(-375 2075);
FORCEPROP 3 LASTPIN (-375 2125) SIG_NAME GND\g
J 0
(-365 2135);
DISPLAY 0.659574 (-365 2135);
PAINT MONO (-365 2135);
DISPLAY INVISIBLE (-365 2135);
FORCEPROP 2 LAST CDS_LIB mstr_symbols
J 0
(-375 2075);
DISPLAY 0.723404 (-375 2075);
DISPLAY INVISIBLE (-375 2075);
FORCEPROP 1 LAST SIZE 1B
J 0
(-300 2025);
DISPLAY 0.851064 (-300 2025);
PAINT GREEN (-300 2025);
DISPLAY INVISIBLE (-300 2025);
FORCEPROP 1 LAST VOLTAGE 0.0
J 0
(-420 2032);
DISPLAY 0.723404 (-420 2032);
PAINT SKYBLUE (-420 2032);
DISPLAY INVISIBLE (-420 2032);
FORCEPROP 1 LAST BODY_TYPE PLUMBING
J 0
(-420 2032);
DISPLAY 0.340426 (-420 2032);
PAINT GREEN (-420 2032);
DISPLAY INVISIBLE (-420 2032);
FORCEPROP 1 LAST HDL_POWER GND
J 0
(-375 2225);
DISPLAY 0.851064 (-375 2225);
PAINT GREEN (-375 2225);
DISPLAY INVISIBLE (-375 2225);
FORCEPROP 1 LAST PATH I141
J 0
(-300 2075);
DISPLAY 0.872340 (-300 2075);
PAINT AQUA (-300 2075);
DISPLAY INVISIBLE (-300 2075);
FORCEADD TAP..1
R 2
(-7875 3650);
FORCEPROP 3 LASTPIN (-7825 3650) SIG_NAME M_E_CPU1_SB_CB<4>
J 0
(-7815 3660);
DISPLAY 0.659574 (-7815 3660);
PAINT MONO (-7815 3660);
DISPLAY INVISIBLE (-7815 3660);
FORCEPROP 1 LASTPIN (-7825 3650) BN 4
J 2
(-7813 3658);
DISPLAY 0.489362 (-7813 3658);
PAINT GREEN (-7813 3658);
FORCEPROP 2 LAST CDS_LIB mstr_standard
J 0
(-7875 3650);
DISPLAY 0.723404 (-7875 3650);
PAINT MONO (-7875 3650);
DISPLAY INVISIBLE (-7875 3650);
FORCEPROP 1 LAST BODY_TYPE PLUMBING
J 2
(-7875 3700);
DISPLAY 0.872340 (-7875 3700);
PAINT GREEN (-7875 3700);
DISPLAY INVISIBLE (-7875 3700);
FORCEPROP 1 LAST HDL_TAP TRUE
J 2
(-8200 3525);
DISPLAY 0.872340 (-8200 3525);
DISPLAY INVISIBLE (-8200 3525);
FORCEPROP 1 LAST PATH I15
J 2
(-7873 3650);
DISPLAY 0.872340 (-7873 3650);
PAINT GREEN (-7873 3650);
DISPLAY INVISIBLE (-7873 3650);
FORCEADD TAP..1
R 2
(-7875 3700);
FORCEPROP 3 LASTPIN (-7825 3700) SIG_NAME M_E_CPU1_SB_CB<5>
J 0
(-7815 3710);
DISPLAY 0.659574 (-7815 3710);
PAINT MONO (-7815 3710);
DISPLAY INVISIBLE (-7815 3710);
FORCEPROP 1 LASTPIN (-7825 3700) BN 5
J 2
(-7813 3708);
DISPLAY 0.489362 (-7813 3708);
PAINT GREEN (-7813 3708);
FORCEPROP 2 LAST CDS_LIB mstr_standard
J 0
(-7875 3700);
DISPLAY 0.723404 (-7875 3700);
PAINT MONO (-7875 3700);
DISPLAY INVISIBLE (-7875 3700);
FORCEPROP 1 LAST BODY_TYPE PLUMBING
J 2
(-7875 3750);
DISPLAY 0.872340 (-7875 3750);
PAINT GREEN (-7875 3750);
DISPLAY INVISIBLE (-7875 3750);
FORCEPROP 1 LAST HDL_TAP TRUE
J 2
(-8200 3575);
DISPLAY 0.872340 (-8200 3575);
DISPLAY INVISIBLE (-8200 3575);
FORCEPROP 1 LAST PATH I16
J 2
(-7873 3700);
DISPLAY 0.872340 (-7873 3700);
PAINT GREEN (-7873 3700);
DISPLAY INVISIBLE (-7873 3700);
FORCEADD TAP..1
R 2
(-7875 3750);
FORCEPROP 3 LASTPIN (-7825 3750) SIG_NAME M_E_CPU1_SB_CB<6>
J 0
(-7815 3760);
DISPLAY 0.659574 (-7815 3760);
PAINT MONO (-7815 3760);
DISPLAY INVISIBLE (-7815 3760);
FORCEPROP 1 LASTPIN (-7825 3750) BN 6
J 2
(-7813 3758);
DISPLAY 0.489362 (-7813 3758);
PAINT GREEN (-7813 3758);
FORCEPROP 2 LAST CDS_LIB mstr_standard
J 0
(-7875 3750);
DISPLAY 0.723404 (-7875 3750);
PAINT MONO (-7875 3750);
DISPLAY INVISIBLE (-7875 3750);
FORCEPROP 1 LAST BODY_TYPE PLUMBING
J 2
(-7875 3800);
DISPLAY 0.872340 (-7875 3800);
PAINT GREEN (-7875 3800);
DISPLAY INVISIBLE (-7875 3800);
FORCEPROP 1 LAST HDL_TAP TRUE
J 2
(-8200 3625);
DISPLAY 0.872340 (-8200 3625);
DISPLAY INVISIBLE (-8200 3625);
FORCEPROP 1 LAST PATH I17
J 2
(-7873 3750);
DISPLAY 0.872340 (-7873 3750);
PAINT GREEN (-7873 3750);
DISPLAY INVISIBLE (-7873 3750);
FORCEADD SCONN288_DDR506112002KQ..3
(-1275 4000);
FORCEPROP 1 LAST LOCATION J32
J 0
(-1725 5975);
DISPLAY 0.468085 (-1725 5975);
PAINT SKYBLUE (-1725 5975);
FORCEPROP 0 LAST $SEC 3
J 0
(-1725 6125);
DISPLAY 0.680851 (-1725 6125);
PAINT MONO (-1725 6125);
DISPLAY INVISIBLE (-1725 6125);
FORCEPROP 2 LAST CDS_SEC 3
J 0
(-1725 6125);
DISPLAY 1.021277 (-1725 6125);
DISPLAY INVISIBLE (-1725 6125);
FORCEPROP 0 LASTPIN (-675 2400) $PN G1
J 0
(-665 2410);
DISPLAY 0.680851 (-665 2410);
PAINT MONO (-665 2410);
FORCEPROP 0 LASTPIN (-675 2350) $PN G2
J 0
(-665 2360);
DISPLAY 0.680851 (-665 2360);
PAINT MONO (-665 2360);
FORCEPROP 0 LASTPIN (-675 2300) $PN G3
J 0
(-665 2310);
DISPLAY 0.680851 (-665 2310);
PAINT MONO (-665 2310);
FORCEPROP 0 LASTPIN (-1875 5550) $PN 1
J 2
(-1885 5560);
DISPLAY 0.680851 (-1885 5560);
PAINT MONO (-1885 5560);
FORCEPROP 0 LASTPIN (-1875 5600) $PN 145
J 2
(-1885 5610);
DISPLAY 0.680851 (-1885 5610);
PAINT MONO (-1885 5610);
FORCEPROP 0 LASTPIN (-1875 5650) $PN 146
J 2
(-1885 5660);
DISPLAY 0.680851 (-1885 5660);
PAINT MONO (-1885 5660);
FORCEPROP 0 LASTPIN (-675 2500) $PN 6
J 0
(-665 2510);
DISPLAY 0.680851 (-665 2510);
PAINT MONO (-665 2510);
FORCEPROP 0 LASTPIN (-675 2550) $PN 8
J 0
(-665 2560);
DISPLAY 0.680851 (-665 2560);
PAINT MONO (-665 2560);
FORCEPROP 0 LASTPIN (-675 2600) $PN 10
J 0
(-665 2610);
DISPLAY 0.680851 (-665 2610);
PAINT MONO (-665 2610);
FORCEPROP 0 LASTPIN (-675 2650) $PN 13
J 0
(-665 2660);
DISPLAY 0.680851 (-665 2660);
PAINT MONO (-665 2660);
FORCEPROP 0 LASTPIN (-675 2700) $PN 15
J 0
(-665 2710);
DISPLAY 0.680851 (-665 2710);
PAINT MONO (-665 2710);
FORCEPROP 0 LASTPIN (-675 2750) $PN 17
J 0
(-665 2760);
DISPLAY 0.680851 (-665 2760);
PAINT MONO (-665 2760);
FORCEPROP 0 LASTPIN (-675 2800) $PN 19
J 0
(-665 2810);
DISPLAY 0.680851 (-665 2810);
PAINT MONO (-665 2810);
FORCEPROP 0 LASTPIN (-675 2850) $PN 21
J 0
(-665 2860);
DISPLAY 0.680851 (-665 2860);
PAINT MONO (-665 2860);
FORCEPROP 0 LASTPIN (-675 2900) $PN 24
J 0
(-665 2910);
DISPLAY 0.680851 (-665 2910);
PAINT MONO (-665 2910);
FORCEPROP 0 LASTPIN (-675 2950) $PN 26
J 0
(-665 2960);
DISPLAY 0.680851 (-665 2960);
PAINT MONO (-665 2960);
FORCEPROP 0 LASTPIN (-675 3000) $PN 28
J 0
(-665 3010);
DISPLAY 0.680851 (-665 3010);
PAINT MONO (-665 3010);
FORCEPROP 0 LASTPIN (-675 3050) $PN 30
J 0
(-665 3060);
DISPLAY 0.680851 (-665 3060);
PAINT MONO (-665 3060);
FORCEPROP 0 LASTPIN (-675 3100) $PN 32
J 0
(-665 3110);
DISPLAY 0.680851 (-665 3110);
PAINT MONO (-665 3110);
FORCEPROP 0 LASTPIN (-675 3150) $PN 35
J 0
(-665 3160);
DISPLAY 0.680851 (-665 3160);
PAINT MONO (-665 3160);
FORCEPROP 0 LASTPIN (-675 3200) $PN 37
J 0
(-665 3210);
DISPLAY 0.680851 (-665 3210);
PAINT MONO (-665 3210);
FORCEPROP 0 LASTPIN (-675 3250) $PN 39
J 0
(-665 3260);
DISPLAY 0.680851 (-665 3260);
PAINT MONO (-665 3260);
FORCEPROP 0 LASTPIN (-675 3300) $PN 41
J 0
(-665 3310);
DISPLAY 0.680851 (-665 3310);
PAINT MONO (-665 3310);
FORCEPROP 0 LASTPIN (-675 3350) $PN 43
J 0
(-665 3360);
DISPLAY 0.680851 (-665 3360);
PAINT MONO (-665 3360);
FORCEPROP 0 LASTPIN (-675 3400) $PN 46
J 0
(-665 3410);
DISPLAY 0.680851 (-665 3410);
PAINT MONO (-665 3410);
FORCEPROP 0 LASTPIN (-675 3450) $PN 48
J 0
(-665 3460);
DISPLAY 0.680851 (-665 3460);
PAINT MONO (-665 3460);
FORCEPROP 0 LASTPIN (-675 3500) $PN 50
J 0
(-665 3510);
DISPLAY 0.680851 (-665 3510);
PAINT MONO (-665 3510);
FORCEPROP 0 LASTPIN (-675 3550) $PN 52
J 0
(-665 3560);
DISPLAY 0.680851 (-665 3560);
PAINT MONO (-665 3560);
FORCEPROP 0 LASTPIN (-675 3600) $PN 54
J 0
(-665 3610);
DISPLAY 0.680851 (-665 3610);
PAINT MONO (-665 3610);
FORCEPROP 0 LASTPIN (-675 3650) $PN 57
J 0
(-665 3660);
DISPLAY 0.680851 (-665 3660);
PAINT MONO (-665 3660);
FORCEPROP 0 LASTPIN (-675 3700) $PN 59
J 0
(-665 3710);
DISPLAY 0.680851 (-665 3710);
PAINT MONO (-665 3710);
FORCEPROP 0 LASTPIN (-675 3750) $PN 61
J 0
(-665 3760);
DISPLAY 0.680851 (-665 3760);
PAINT MONO (-665 3760);
FORCEPROP 0 LASTPIN (-675 3800) $PN 63
J 0
(-665 3810);
DISPLAY 0.680851 (-665 3810);
PAINT MONO (-665 3810);
FORCEPROP 0 LASTPIN (-675 3850) $PN 65
J 0
(-665 3860);
DISPLAY 0.680851 (-665 3860);
PAINT MONO (-665 3860);
FORCEPROP 0 LASTPIN (-675 3900) $PN 67
J 0
(-665 3910);
DISPLAY 0.680851 (-665 3910);
PAINT MONO (-665 3910);
FORCEPROP 0 LASTPIN (-675 3950) $PN 69
J 0
(-665 3960);
DISPLAY 0.680851 (-665 3960);
PAINT MONO (-665 3960);
FORCEPROP 0 LASTPIN (-675 4000) $PN 71
J 0
(-665 4010);
DISPLAY 0.680851 (-665 4010);
PAINT MONO (-665 4010);
FORCEPROP 0 LASTPIN (-675 4050) $PN 73
J 0
(-665 4060);
DISPLAY 0.680851 (-665 4060);
PAINT MONO (-665 4060);
FORCEPROP 0 LASTPIN (-675 4100) $PN 75
J 0
(-665 4110);
DISPLAY 0.680851 (-665 4110);
PAINT MONO (-665 4110);
FORCEPROP 0 LASTPIN (-675 4150) $PN 77
J 0
(-665 4160);
DISPLAY 0.680851 (-665 4160);
PAINT MONO (-665 4160);
FORCEPROP 0 LASTPIN (-675 4200) $PN 79
J 0
(-665 4210);
DISPLAY 0.680851 (-665 4210);
PAINT MONO (-665 4210);
FORCEPROP 0 LASTPIN (-675 4250) $PN 81
J 0
(-665 4260);
DISPLAY 0.680851 (-665 4260);
PAINT MONO (-665 4260);
FORCEPROP 0 LASTPIN (-675 4300) $PN 83
J 0
(-665 4310);
DISPLAY 0.680851 (-665 4310);
PAINT MONO (-665 4310);
FORCEPROP 0 LASTPIN (-675 4350) $PN 85
J 0
(-665 4360);
DISPLAY 0.680851 (-665 4360);
PAINT MONO (-665 4360);
FORCEPROP 0 LASTPIN (-675 4400) $PN 88
J 0
(-665 4410);
DISPLAY 0.680851 (-665 4410);
PAINT MONO (-665 4410);
FORCEPROP 0 LASTPIN (-675 4450) $PN 90
J 0
(-665 4460);
DISPLAY 0.680851 (-665 4460);
PAINT MONO (-665 4460);
FORCEPROP 0 LASTPIN (-675 4500) $PN 92
J 0
(-665 4510);
DISPLAY 0.680851 (-665 4510);
PAINT MONO (-665 4510);
FORCEPROP 0 LASTPIN (-675 4550) $PN 95
J 0
(-665 4560);
DISPLAY 0.680851 (-665 4560);
PAINT MONO (-665 4560);
FORCEPROP 0 LASTPIN (-675 4600) $PN 97
J 0
(-665 4610);
DISPLAY 0.680851 (-665 4610);
PAINT MONO (-665 4610);
FORCEPROP 0 LASTPIN (-675 4650) $PN 99
J 0
(-665 4660);
DISPLAY 0.680851 (-665 4660);
PAINT MONO (-665 4660);
FORCEPROP 0 LASTPIN (-675 4700) $PN 101
J 0
(-665 4710);
DISPLAY 0.680851 (-665 4710);
PAINT MONO (-665 4710);
FORCEPROP 0 LASTPIN (-675 4750) $PN 103
J 0
(-665 4760);
DISPLAY 0.680851 (-665 4760);
PAINT MONO (-665 4760);
FORCEPROP 0 LASTPIN (-675 4800) $PN 106
J 0
(-665 4810);
DISPLAY 0.680851 (-665 4810);
PAINT MONO (-665 4810);
FORCEPROP 0 LASTPIN (-675 4850) $PN 108
J 0
(-665 4860);
DISPLAY 0.680851 (-665 4860);
PAINT MONO (-665 4860);
FORCEPROP 0 LASTPIN (-675 4900) $PN 110
J 0
(-665 4910);
DISPLAY 0.680851 (-665 4910);
PAINT MONO (-665 4910);
FORCEPROP 0 LASTPIN (-675 4950) $PN 112
J 0
(-665 4960);
DISPLAY 0.680851 (-665 4960);
PAINT MONO (-665 4960);
FORCEPROP 0 LASTPIN (-675 5000) $PN 114
J 0
(-665 5010);
DISPLAY 0.680851 (-665 5010);
PAINT MONO (-665 5010);
FORCEPROP 0 LASTPIN (-675 5050) $PN 117
J 0
(-665 5060);
DISPLAY 0.680851 (-665 5060);
PAINT MONO (-665 5060);
FORCEPROP 0 LASTPIN (-675 5100) $PN 119
J 0
(-665 5110);
DISPLAY 0.680851 (-665 5110);
PAINT MONO (-665 5110);
FORCEPROP 0 LASTPIN (-675 5150) $PN 121
J 0
(-665 5160);
DISPLAY 0.680851 (-665 5160);
PAINT MONO (-665 5160);
FORCEPROP 0 LASTPIN (-675 5200) $PN 123
J 0
(-665 5210);
DISPLAY 0.680851 (-665 5210);
PAINT MONO (-665 5210);
FORCEPROP 0 LASTPIN (-675 5250) $PN 125
J 0
(-665 5260);
DISPLAY 0.680851 (-665 5260);
PAINT MONO (-665 5260);
FORCEPROP 0 LASTPIN (-675 5300) $PN 128
J 0
(-665 5310);
DISPLAY 0.680851 (-665 5310);
PAINT MONO (-665 5310);
FORCEPROP 0 LASTPIN (-675 5350) $PN 130
J 0
(-665 5360);
DISPLAY 0.680851 (-665 5360);
PAINT MONO (-665 5360);
FORCEPROP 0 LASTPIN (-675 5400) $PN 132
J 0
(-665 5410);
DISPLAY 0.680851 (-665 5410);
PAINT MONO (-665 5410);
FORCEPROP 0 LASTPIN (-675 5450) $PN 134
J 0
(-665 5460);
DISPLAY 0.680851 (-665 5460);
PAINT MONO (-665 5460);
FORCEPROP 0 LASTPIN (-675 5500) $PN 136
J 0
(-665 5510);
DISPLAY 0.680851 (-665 5510);
PAINT MONO (-665 5510);
FORCEPROP 0 LASTPIN (-675 5550) $PN 139
J 0
(-665 5560);
DISPLAY 0.680851 (-665 5560);
PAINT MONO (-665 5560);
FORCEPROP 0 LASTPIN (-675 5600) $PN 141
J 0
(-665 5610);
DISPLAY 0.680851 (-665 5610);
PAINT MONO (-665 5610);
FORCEPROP 0 LASTPIN (-675 5650) $PN 143
J 0
(-665 5660);
DISPLAY 0.680851 (-665 5660);
PAINT MONO (-665 5660);
FORCEPROP 0 LASTPIN (-1875 2400) $PN 151
J 2
(-1885 2410);
DISPLAY 0.680851 (-1885 2410);
PAINT MONO (-1885 2410);
FORCEPROP 0 LASTPIN (-1875 2450) $PN 153
J 2
(-1885 2460);
DISPLAY 0.680851 (-1885 2460);
PAINT MONO (-1885 2460);
FORCEPROP 0 LASTPIN (-1875 2500) $PN 155
J 2
(-1885 2510);
DISPLAY 0.680851 (-1885 2510);
PAINT MONO (-1885 2510);
FORCEPROP 0 LASTPIN (-1875 2550) $PN 158
J 2
(-1885 2560);
DISPLAY 0.680851 (-1885 2560);
PAINT MONO (-1885 2560);
FORCEPROP 0 LASTPIN (-1875 2600) $PN 160
J 2
(-1885 2610);
DISPLAY 0.680851 (-1885 2610);
PAINT MONO (-1885 2610);
FORCEPROP 0 LASTPIN (-1875 2650) $PN 162
J 2
(-1885 2660);
DISPLAY 0.680851 (-1885 2660);
PAINT MONO (-1885 2660);
FORCEPROP 0 LASTPIN (-1875 2700) $PN 164
J 2
(-1885 2710);
DISPLAY 0.680851 (-1885 2710);
PAINT MONO (-1885 2710);
FORCEPROP 0 LASTPIN (-1875 2750) $PN 166
J 2
(-1885 2760);
DISPLAY 0.680851 (-1885 2760);
PAINT MONO (-1885 2760);
FORCEPROP 0 LASTPIN (-1875 2800) $PN 169
J 2
(-1885 2810);
DISPLAY 0.680851 (-1885 2810);
PAINT MONO (-1885 2810);
FORCEPROP 0 LASTPIN (-1875 2850) $PN 171
J 2
(-1885 2860);
DISPLAY 0.680851 (-1885 2860);
PAINT MONO (-1885 2860);
FORCEPROP 0 LASTPIN (-1875 2900) $PN 173
J 2
(-1885 2910);
DISPLAY 0.680851 (-1885 2910);
PAINT MONO (-1885 2910);
FORCEPROP 0 LASTPIN (-1875 2950) $PN 175
J 2
(-1885 2960);
DISPLAY 0.680851 (-1885 2960);
PAINT MONO (-1885 2960);
FORCEPROP 0 LASTPIN (-1875 3000) $PN 177
J 2
(-1885 3010);
DISPLAY 0.680851 (-1885 3010);
PAINT MONO (-1885 3010);
FORCEPROP 0 LASTPIN (-1875 3050) $PN 180
J 2
(-1885 3060);
DISPLAY 0.680851 (-1885 3060);
PAINT MONO (-1885 3060);
FORCEPROP 0 LASTPIN (-1875 3100) $PN 182
J 2
(-1885 3110);
DISPLAY 0.680851 (-1885 3110);
PAINT MONO (-1885 3110);
FORCEPROP 0 LASTPIN (-1875 3150) $PN 184
J 2
(-1885 3160);
DISPLAY 0.680851 (-1885 3160);
PAINT MONO (-1885 3160);
FORCEPROP 0 LASTPIN (-1875 3200) $PN 186
J 2
(-1885 3210);
DISPLAY 0.680851 (-1885 3210);
PAINT MONO (-1885 3210);
FORCEPROP 0 LASTPIN (-1875 3250) $PN 188
J 2
(-1885 3260);
DISPLAY 0.680851 (-1885 3260);
PAINT MONO (-1885 3260);
FORCEPROP 0 LASTPIN (-1875 3300) $PN 191
J 2
(-1885 3310);
DISPLAY 0.680851 (-1885 3310);
PAINT MONO (-1885 3310);
FORCEPROP 0 LASTPIN (-1875 3350) $PN 193
J 2
(-1885 3360);
DISPLAY 0.680851 (-1885 3360);
PAINT MONO (-1885 3360);
FORCEPROP 0 LASTPIN (-1875 3400) $PN 195
J 2
(-1885 3410);
DISPLAY 0.680851 (-1885 3410);
PAINT MONO (-1885 3410);
FORCEPROP 0 LASTPIN (-1875 3450) $PN 197
J 2
(-1885 3460);
DISPLAY 0.680851 (-1885 3460);
PAINT MONO (-1885 3460);
FORCEPROP 0 LASTPIN (-1875 3500) $PN 199
J 2
(-1885 3510);
DISPLAY 0.680851 (-1885 3510);
PAINT MONO (-1885 3510);
FORCEPROP 0 LASTPIN (-1875 3550) $PN 202
J 2
(-1885 3560);
DISPLAY 0.680851 (-1885 3560);
PAINT MONO (-1885 3560);
FORCEPROP 0 LASTPIN (-1875 3600) $PN 204
J 2
(-1885 3610);
DISPLAY 0.680851 (-1885 3610);
PAINT MONO (-1885 3610);
FORCEPROP 0 LASTPIN (-1875 3650) $PN 206
J 2
(-1885 3660);
DISPLAY 0.680851 (-1885 3660);
PAINT MONO (-1885 3660);
FORCEPROP 0 LASTPIN (-1875 3700) $PN 208
J 2
(-1885 3710);
DISPLAY 0.680851 (-1885 3710);
PAINT MONO (-1885 3710);
FORCEPROP 0 LASTPIN (-1875 3750) $PN 210
J 2
(-1885 3760);
DISPLAY 0.680851 (-1885 3760);
PAINT MONO (-1885 3760);
FORCEPROP 0 LASTPIN (-1875 3800) $PN 212
J 2
(-1885 3810);
DISPLAY 0.680851 (-1885 3810);
PAINT MONO (-1885 3810);
FORCEPROP 0 LASTPIN (-1875 3850) $PN 214
J 2
(-1885 3860);
DISPLAY 0.680851 (-1885 3860);
PAINT MONO (-1885 3860);
FORCEPROP 0 LASTPIN (-1875 3900) $PN 216
J 2
(-1885 3910);
DISPLAY 0.680851 (-1885 3910);
PAINT MONO (-1885 3910);
FORCEPROP 0 LASTPIN (-1875 3950) $PN 219
J 2
(-1885 3960);
DISPLAY 0.680851 (-1885 3960);
PAINT MONO (-1885 3960);
FORCEPROP 0 LASTPIN (-1875 4000) $PN 222
J 2
(-1885 4010);
DISPLAY 0.680851 (-1885 4010);
PAINT MONO (-1885 4010);
FORCEPROP 0 LASTPIN (-1875 4050) $PN 224
J 2
(-1885 4060);
DISPLAY 0.680851 (-1885 4060);
PAINT MONO (-1885 4060);
FORCEPROP 0 LASTPIN (-1875 4100) $PN 226
J 2
(-1885 4110);
DISPLAY 0.680851 (-1885 4110);
PAINT MONO (-1885 4110);
FORCEPROP 0 LASTPIN (-1875 4150) $PN 228
J 2
(-1885 4160);
DISPLAY 0.680851 (-1885 4160);
PAINT MONO (-1885 4160);
FORCEPROP 0 LASTPIN (-1875 4200) $PN 230
J 2
(-1885 4210);
DISPLAY 0.680851 (-1885 4210);
PAINT MONO (-1885 4210);
FORCEPROP 0 LASTPIN (-1875 4250) $PN 233
J 2
(-1885 4260);
DISPLAY 0.680851 (-1885 4260);
PAINT MONO (-1885 4260);
FORCEPROP 0 LASTPIN (-1875 4300) $PN 235
J 2
(-1885 4310);
DISPLAY 0.680851 (-1885 4310);
PAINT MONO (-1885 4310);
FORCEPROP 0 LASTPIN (-1875 4350) $PN 237
J 2
(-1885 4360);
DISPLAY 0.680851 (-1885 4360);
PAINT MONO (-1885 4360);
FORCEPROP 0 LASTPIN (-1875 4400) $PN 240
J 2
(-1885 4410);
DISPLAY 0.680851 (-1885 4410);
PAINT MONO (-1885 4410);
FORCEPROP 0 LASTPIN (-1875 4450) $PN 242
J 2
(-1885 4460);
DISPLAY 0.680851 (-1885 4460);
PAINT MONO (-1885 4460);
FORCEPROP 0 LASTPIN (-1875 4500) $PN 244
J 2
(-1885 4510);
DISPLAY 0.680851 (-1885 4510);
PAINT MONO (-1885 4510);
FORCEPROP 0 LASTPIN (-1875 4550) $PN 246
J 2
(-1885 4560);
DISPLAY 0.680851 (-1885 4560);
PAINT MONO (-1885 4560);
FORCEPROP 0 LASTPIN (-1875 4600) $PN 248
J 2
(-1885 4610);
DISPLAY 0.680851 (-1885 4610);
PAINT MONO (-1885 4610);
FORCEPROP 0 LASTPIN (-1875 4650) $PN 251
J 2
(-1885 4660);
DISPLAY 0.680851 (-1885 4660);
PAINT MONO (-1885 4660);
FORCEPROP 0 LASTPIN (-1875 4700) $PN 253
J 2
(-1885 4710);
DISPLAY 0.680851 (-1885 4710);
PAINT MONO (-1885 4710);
FORCEPROP 0 LASTPIN (-1875 4750) $PN 255
J 2
(-1885 4760);
DISPLAY 0.680851 (-1885 4760);
PAINT MONO (-1885 4760);
FORCEPROP 0 LASTPIN (-1875 4800) $PN 257
J 2
(-1885 4810);
DISPLAY 0.680851 (-1885 4810);
PAINT MONO (-1885 4810);
FORCEPROP 0 LASTPIN (-1875 4850) $PN 259
J 2
(-1885 4860);
DISPLAY 0.680851 (-1885 4860);
PAINT MONO (-1885 4860);
FORCEPROP 0 LASTPIN (-1875 4900) $PN 262
J 2
(-1885 4910);
DISPLAY 0.680851 (-1885 4910);
PAINT MONO (-1885 4910);
FORCEPROP 0 LASTPIN (-1875 4950) $PN 264
J 2
(-1885 4960);
DISPLAY 0.680851 (-1885 4960);
PAINT MONO (-1885 4960);
FORCEPROP 0 LASTPIN (-1875 5000) $PN 266
J 2
(-1885 5010);
DISPLAY 0.680851 (-1885 5010);
PAINT MONO (-1885 5010);
FORCEPROP 0 LASTPIN (-1875 5050) $PN 268
J 2
(-1885 5060);
DISPLAY 0.680851 (-1885 5060);
PAINT MONO (-1885 5060);
FORCEPROP 0 LASTPIN (-1875 5100) $PN 270
J 2
(-1885 5110);
DISPLAY 0.680851 (-1885 5110);
PAINT MONO (-1885 5110);
FORCEPROP 0 LASTPIN (-1875 5150) $PN 273
J 2
(-1885 5160);
DISPLAY 0.680851 (-1885 5160);
PAINT MONO (-1885 5160);
FORCEPROP 0 LASTPIN (-1875 5200) $PN 275
J 2
(-1885 5210);
DISPLAY 0.680851 (-1885 5210);
PAINT MONO (-1885 5210);
FORCEPROP 0 LASTPIN (-1875 5250) $PN 277
J 2
(-1885 5260);
DISPLAY 0.680851 (-1885 5260);
PAINT MONO (-1885 5260);
FORCEPROP 0 LASTPIN (-1875 5300) $PN 279
J 2
(-1885 5310);
DISPLAY 0.680851 (-1885 5310);
PAINT MONO (-1885 5310);
FORCEPROP 0 LASTPIN (-1875 5350) $PN 281
J 2
(-1885 5360);
DISPLAY 0.680851 (-1885 5360);
PAINT MONO (-1885 5360);
FORCEPROP 0 LASTPIN (-1875 5400) $PN 284
J 2
(-1885 5410);
DISPLAY 0.680851 (-1885 5410);
PAINT MONO (-1885 5410);
FORCEPROP 0 LASTPIN (-1875 5450) $PN 286
J 2
(-1885 5460);
DISPLAY 0.680851 (-1885 5460);
PAINT MONO (-1885 5460);
FORCEPROP 0 LASTPIN (-1875 5500) $PN 288
J 2
(-1885 5510);
DISPLAY 0.680851 (-1885 5510);
PAINT MONO (-1885 5510);
FORCEPROP 2 LAST PART_TYPE SMLF
J 0
(-1725 6075);
DISPLAY 1.021277 (-1725 6075);
FORCEPROP 1 LAST MATERIAL IO
J 0
(-1725 5825);
DISPLAY 0.468085 (-1725 5825);
PAINT SKYBLUE (-1725 5825);
FORCEPROP 2 LAST VALUE SCONN288_DDR506112002KQ
J 0
(-1725 6025);
DISPLAY 0.489362 (-1725 6025);
PAINT SKYBLUE (-1725 6025);
FORCEPROP 1 LAST CDS_LMAN_SYM_OUTLINE -450,1800,450,-1750
J 0
(-1275 4000);
DISPLAY 0.468085 (-1275 4000);
PAINT GREEN (-1275 4000);
DISPLAY INVISIBLE (-1275 4000);
FORCEPROP 1 LAST NEEDS_NO_SIZE TRUE
J 0
(-1275 4000);
DISPLAY 0.723404 (-1275 4000);
PAINT GREEN (-1275 4000);
DISPLAY INVISIBLE (-1275 4000);
FORCEPROP 2 LAST CDS_LIB pure_quanta
J 0
(-1275 4000);
DISPLAY INVISIBLE (-1275 4000);
FORCEPROP 1 LAST PATH I175
J 0
(-1275 4000);
DISPLAY 0.723404 (-1275 4000);
PAINT GREEN (-1275 4000);
DISPLAY INVISIBLE (-1275 4000);
FORCEPROP 1 LAST PART_NUMBER DFHST8FS479
J 0
(-1725 5900);
DISPLAY 0.468085 (-1725 5900);
PAINT SKYBLUE (-1725 5900);
DISPLAY INVISIBLE (-1725 5900);
FORCEADD TAP..1
R 2
(-7875 3900);
FORCEPROP 3 LASTPIN (-7825 3900) SIG_NAME M_E_CPU1_SA_CB<0>
J 0
(-7815 3910);
DISPLAY 0.659574 (-7815 3910);
PAINT MONO (-7815 3910);
DISPLAY INVISIBLE (-7815 3910);
FORCEPROP 1 LASTPIN (-7825 3900) BN 0
J 2
(-7813 3908);
DISPLAY 0.489362 (-7813 3908);
PAINT GREEN (-7813 3908);
FORCEPROP 2 LAST CDS_LIB mstr_standard
J 0
(-7875 3900);
DISPLAY 0.723404 (-7875 3900);
PAINT MONO (-7875 3900);
DISPLAY INVISIBLE (-7875 3900);
FORCEPROP 1 LAST BODY_TYPE PLUMBING
J 2
(-7875 3950);
DISPLAY 0.872340 (-7875 3950);
PAINT GREEN (-7875 3950);
DISPLAY INVISIBLE (-7875 3950);
FORCEPROP 1 LAST HDL_TAP TRUE
J 2
(-8200 3775);
DISPLAY 0.872340 (-8200 3775);
DISPLAY INVISIBLE (-8200 3775);
FORCEPROP 1 LAST PATH I18
J 2
(-7873 3900);
DISPLAY 0.872340 (-7873 3900);
PAINT GREEN (-7873 3900);
DISPLAY INVISIBLE (-7873 3900);
FORCEADD Q_CAP..1
R 2
(-8800 3475);
FORCEPROP 1 LAST LOCATION C152
J 2
(-8850 3575);
DISPLAY 0.489362 (-8850 3575);
PAINT SKYBLUE (-8850 3575);
FORCEPROP 0 LAST $SEC 1
J 0
(-8850 3625);
DISPLAY 0.680851 (-8850 3625);
PAINT MONO (-8850 3625);
DISPLAY INVISIBLE (-8850 3625);
FORCEPROP 0 LAST CDS_SEC 1
J 0
(-8850 3625);
DISPLAY 1.021277 (-8850 3625);
DISPLAY INVISIBLE (-8850 3625);
FORCEPROP 1 LASTPIN (-8800 3575) $PN 1
J 2
(-8810 3555);
DISPLAY 0.489362 (-8810 3555);
PAINT MONO (-8810 3555);
FORCEPROP 1 LASTPIN (-8800 3375) $PN 2
J 2
(-8810 3355);
DISPLAY 0.489362 (-8810 3355);
PAINT MONO (-8810 3355);
FORCEPROP 1 LAST PACK_TYPE 0402
J 2
(-8850 3275);
DISPLAY 0.489362 (-8850 3275);
PAINT SKYBLUE (-8850 3275);
FORCEPROP 1 LAST VALUE 0.1UF
J 2
(-8850 3525);
DISPLAY 0.489362 (-8850 3525);
PAINT SKYBLUE (-8850 3525);
FORCEPROP 1 LAST VOLTAGE 25V
J 2
(-8850 3475);
DISPLAY 0.489362 (-8850 3475);
PAINT SKYBLUE (-8850 3475);
FORCEPROP 1 LAST TOLERANCE 10%
J 2
(-8850 3425);
DISPLAY 0.489362 (-8850 3425);
PAINT SKYBLUE (-8850 3425);
FORCEPROP 1 LAST MATERIAL X7R
J 2
(-8850 3375);
DISPLAY 0.489362 (-8850 3375);
PAINT SKYBLUE (-8850 3375);
FORCEPROP 0 LAST BOM_COST MEM
J 2
(-8855 3620);
DISPLAY 0.595745 (-8855 3620);
PAINT MONO (-8855 3620);
DISPLAY INVISIBLE (-8855 3620);
FORCEPROP 2 LAST CDS_LIB pure_quanta
J 0
(-8800 3475);
DISPLAY INVISIBLE (-8800 3475);
FORCEPROP 2 LAST ROOM 
J 2
(-8855 3620);
DISPLAY 0.595745 (-8855 3620);
PAINT RED (-8855 3620);
DISPLAY INVISIBLE (-8855 3620);
FORCEPROP 1 LAST PATH I185
J 2
(-8850 3625);
DISPLAY 0.978723 (-8850 3625);
PAINT WHITE (-8850 3625);
DISPLAY INVISIBLE (-8850 3625);
FORCEPROP 1 LAST PART_NUMBER CH4104K1B00
J 2
(-8850 3325);
DISPLAY 0.489362 (-8850 3325);
PAINT SKYBLUE (-8850 3325);
DISPLAY INVISIBLE (-8850 3325);
FORCEADD GND..1
(-8800 3250);
FORCEPROP 3 LASTPIN (-8800 3300) SIG_NAME GND\g
J 0
(-8790 3310);
DISPLAY 0.659574 (-8790 3310);
PAINT MONO (-8790 3310);
DISPLAY INVISIBLE (-8790 3310);
FORCEPROP 2 LAST CDS_LIB mstr_symbols
J 0
(-8800 3250);
DISPLAY 0.808511 (-8800 3250);
DISPLAY INVISIBLE (-8800 3250);
FORCEPROP 1 LAST SIZE 1B
J 0
(-8725 3200);
DISPLAY 0.723404 (-8725 3200);
PAINT GREEN (-8725 3200);
DISPLAY INVISIBLE (-8725 3200);
FORCEPROP 2 LAST BOM_COST MEM
J 0
(-8775 3375);
DISPLAY 0.659574 (-8775 3375);
DISPLAY INVISIBLE (-8775 3375);
FORCEPROP 1 LAST VOLTAGE 0
J 0
(-8820 3345);
DISPLAY 0.829787 (-8820 3345);
PAINT SKYBLUE (-8820 3345);
DISPLAY INVISIBLE (-8820 3345);
FORCEPROP 2 LAST ROOM MEM_EFGH_DECOUPLING_CAPS
J 0
(-8775 3325);
DISPLAY 0.659574 (-8775 3325);
PAINT RED (-8775 3325);
DISPLAY INVISIBLE (-8775 3325);
FORCEPROP 1 LAST BODY_TYPE PLUMBING
J 0
(-8845 3207);
DISPLAY 0.276596 (-8845 3207);
PAINT GREEN (-8845 3207);
DISPLAY INVISIBLE (-8845 3207);
FORCEPROP 1 LAST HDL_POWER GND
J 0
(-8800 3400);
DISPLAY 0.723404 (-8800 3400);
PAINT GREEN (-8800 3400);
DISPLAY INVISIBLE (-8800 3400);
FORCEPROP 1 LAST PATH I186
J 0
(-8725 3250);
DISPLAY 0.872340 (-8725 3250);
PAINT AQUA (-8725 3250);
DISPLAY INVISIBLE (-8725 3250);
FORCEADD OFFPAGE..6
(-9125 2400);
FORCEPROP 2 LAST $XR4 103 
J 0
(-9374 2256);
DISPLAY 0.638298 (-9374 2256);
PAINT MONO (-9374 2256);
FORCEPROP 2 LAST $XR3 101 
J 0
(-9374 2292);
DISPLAY 0.638298 (-9374 2292);
PAINT MONO (-9374 2292);
FORCEPROP 2 LAST $XR2 100 
J 0
(-9374 2328);
DISPLAY 0.638298 (-9374 2328);
PAINT MONO (-9374 2328);
FORCEPROP 2 LAST $XR1 99 
J 0
(-9374 2364);
DISPLAY 0.638298 (-9374 2364);
PAINT MONO (-9374 2364);
FORCEPROP 2 LAST $XR0 98 
J 0
(-9374 2400);
DISPLAY 0.638298 (-9374 2400);
PAINT MONO (-9374 2400);
FORCEPROP 2 LAST CDS_LIB mstr_standard
J 0
(-9125 2400);
DISPLAY 0.808511 (-9125 2400);
DISPLAY INVISIBLE (-9125 2400);
FORCEPROP 1 LAST OFFPAGE TRUE
J 0
(-8800 2275);
DISPLAY 0.872340 (-8800 2275);
PAINT GREEN (-8800 2275);
DISPLAY INVISIBLE (-8800 2275);
FORCEPROP 1 LAST COMMENT_BODY TRUE
J 0
(-9025 2325);
DISPLAY 0.872340 (-9025 2325);
PAINT GREEN (-9025 2325);
DISPLAY INVISIBLE (-9025 2325);
FORCEPROP 2 LAST PATH I187
J 0
(-9075 2475);
DISPLAY 1.021277 (-9075 2475);
DISPLAY INVISIBLE (-9075 2475);
FORCEADD Q_RES..1
R 2
(-8625 2400);
FORCEPROP 1 LAST LOCATION R307
J 2
(-8600 2425);
DISPLAY 0.489362 (-8600 2425);
PAINT SKYBLUE (-8600 2425);
FORCEPROP 0 LAST $SEC 1
J 0
(-8600 2475);
DISPLAY 0.680851 (-8600 2475);
PAINT MONO (-8600 2475);
DISPLAY INVISIBLE (-8600 2475);
FORCEPROP 0 LAST CDS_SEC 1
J 0
(-8600 2475);
DISPLAY 1.021277 (-8600 2475);
DISPLAY INVISIBLE (-8600 2475);
FORCEPROP 1 LASTPIN (-8525 2400) $PN 1
J 2
(-8537 2412);
DISPLAY 0.489362 (-8537 2412);
PAINT MONO (-8537 2412);
FORCEPROP 1 LASTPIN (-8725 2400) $PN 2
J 2
(-8687 2412);
DISPLAY 0.489362 (-8687 2412);
PAINT MONO (-8687 2412);
FORCEPROP 1 LAST VALUE 1K
J 0
(-8625 2350);
DISPLAY 0.489362 (-8625 2350);
PAINT SKYBLUE (-8625 2350);
FORCEPROP 1 LAST TOLERANCE 1%
J 2
(-8500 2375);
DISPLAY 0.489362 (-8500 2375);
PAINT SKYBLUE (-8500 2375);
DISPLAY INVISIBLE (-8500 2375);
FORCEPROP 2 LAST CDS_LIB pure_quanta
J 0
(-8625 2400);
DISPLAY INVISIBLE (-8625 2400);
FORCEPROP 2 LAST BOM_COST MEM
J 0
(-8650 2550);
DISPLAY 0.744681 (-8650 2550);
PAINT WHITE (-8650 2550);
DISPLAY INVISIBLE (-8650 2550);
FORCEPROP 1 LAST WATTAGE 1/16W
J 0
(-8550 2325);
DISPLAY 0.489362 (-8550 2325);
PAINT SKYBLUE (-8550 2325);
DISPLAY INVISIBLE (-8550 2325);
FORCEPROP 1 LAST MATERIAL CHIP
J 0
(-8800 2375);
DISPLAY 0.489362 (-8800 2375);
PAINT SKYBLUE (-8800 2375);
DISPLAY INVISIBLE (-8800 2375);
FORCEPROP 1 LAST PACK_TYPE 0402LF
J 0
(-8800 2325);
DISPLAY 0.489362 (-8800 2325);
PAINT SKYBLUE (-8800 2325);
DISPLAY INVISIBLE (-8800 2325);
FORCEPROP 2 LAST ROOM 
J 0
(-8650 2500);
DISPLAY 0.744681 (-8650 2500);
PAINT RED (-8650 2500);
DISPLAY INVISIBLE (-8650 2500);
FORCEPROP 1 LAST PATH I188
J 2
(-8575 2550);
DISPLAY 0.978723 (-8575 2550);
PAINT WHITE (-8575 2550);
DISPLAY INVISIBLE (-8575 2550);
FORCEPROP 1 LAST PART_NUMBER CS21002FB06
J 0
(-8725 2450);
DISPLAY 0.489362 (-8725 2450);
PAINT SKYBLUE (-8725 2450);
DISPLAY INVISIBLE (-8725 2450);
FORCEADD VCC_CORE..1
(-8500 2725);
FORCEPROP 3 LASTPIN (-8500 2675) SIG_NAME P3V3\g
J 0
(-8490 2685);
DISPLAY 0.659574 (-8490 2685);
PAINT MONO (-8490 2685);
DISPLAY INVISIBLE (-8490 2685);
FORCEPROP 1 LAST HDL_POWER P3V3
J 1
(-8500 2775);
DISPLAY 0.489362 (-8500 2775);
PAINT GREEN (-8500 2775);
FORCEPROP 2 LAST CDS_LIB mstr_symbols
J 0
(-8500 2725);
DISPLAY INVISIBLE (-8500 2725);
FORCEPROP 0 LAST VOLTAGE 3.3
J 0
(-8775 2875);
DISPLAY 1.021277 (-8775 2875);
PAINT SKYBLUE (-8775 2875);
DISPLAY INVISIBLE (-8775 2875);
FORCEPROP 2 LAST ROOM PVCCINFAON_CPU0_CTRL
J 0
(-8500 2825);
DISPLAY 0.808511 (-8500 2825);
PAINT RED (-8500 2825);
DISPLAY INVISIBLE (-8500 2825);
FORCEPROP 1 LAST PATH I189
J 0
(-8450 2750);
DISPLAY 0.872340 (-8450 2750);
PAINT AQUA (-8450 2750);
DISPLAY INVISIBLE (-8450 2750);
FORCEADD TAP..1
R 2
(-7875 3800);
FORCEPROP 3 LASTPIN (-7825 3800) SIG_NAME M_E_CPU1_SB_CB<7>
J 0
(-7815 3810);
DISPLAY 0.659574 (-7815 3810);
PAINT MONO (-7815 3810);
DISPLAY INVISIBLE (-7815 3810);
FORCEPROP 1 LASTPIN (-7825 3800) BN 7
J 2
(-7813 3808);
DISPLAY 0.489362 (-7813 3808);
PAINT GREEN (-7813 3808);
FORCEPROP 2 LAST CDS_LIB mstr_standard
J 0
(-7875 3800);
DISPLAY 0.723404 (-7875 3800);
PAINT MONO (-7875 3800);
DISPLAY INVISIBLE (-7875 3800);
FORCEPROP 1 LAST BODY_TYPE PLUMBING
J 2
(-7875 3850);
DISPLAY 0.872340 (-7875 3850);
PAINT GREEN (-7875 3850);
DISPLAY INVISIBLE (-7875 3850);
FORCEPROP 1 LAST HDL_TAP TRUE
J 2
(-8200 3675);
DISPLAY 0.872340 (-8200 3675);
DISPLAY INVISIBLE (-8200 3675);
FORCEPROP 1 LAST PATH I19
J 2
(-7873 3800);
DISPLAY 0.872340 (-7873 3800);
PAINT GREEN (-7873 3800);
DISPLAY INVISIBLE (-7873 3800);
FORCEADD Q_RES..2
(-8500 2550);
FORCEPROP 1 LAST LOCATION R107
J 0
(-8455 2675);
DISPLAY 0.489362 (-8455 2675);
PAINT SKYBLUE (-8455 2675);
FORCEPROP 0 LAST $SEC 1
J 0
(-8450 2725);
DISPLAY 0.680851 (-8450 2725);
PAINT MONO (-8450 2725);
DISPLAY INVISIBLE (-8450 2725);
FORCEPROP 0 LAST CDS_SEC 1
J 0
(-8450 2725);
DISPLAY 1.021277 (-8450 2725);
DISPLAY INVISIBLE (-8450 2725);
FORCEPROP 1 LASTPIN (-8500 2650) $PN 1
J 0
(-8495 2612);
DISPLAY 0.489362 (-8495 2612);
PAINT MONO (-8495 2612);
FORCEPROP 1 LASTPIN (-8500 2450) $PN 2
J 0
(-8495 2460);
DISPLAY 0.489362 (-8495 2460);
PAINT MONO (-8495 2460);
FORCEPROP 1 LAST PACK_TYPE 0402LF
J 0
(-8450 2500);
DISPLAY 0.489362 (-8450 2500);
PAINT SKYBLUE (-8450 2500);
FORCEPROP 1 LAST MATERIAL EMPTY
J 0
(-8450 2550);
DISPLAY 0.489362 (-8450 2550);
PAINT RED (-8450 2550);
FORCEPROP 1 LAST TOLERANCE 1%
J 0
(-8450 2600);
DISPLAY 0.489362 (-8450 2600);
PAINT SKYBLUE (-8450 2600);
FORCEPROP 1 LAST WATTAGE 1/16W
J 0
(-8450 2575);
DISPLAY 0.489362 (-8450 2575);
PAINT SKYBLUE (-8450 2575);
FORCEPROP 1 LAST VALUE 1K
J 0
(-8455 2625);
DISPLAY 0.489362 (-8455 2625);
PAINT SKYBLUE (-8455 2625);
FORCEPROP 2 LAST BOM_COST MEM
J 0
(-8450 2725);
DISPLAY 0.808511 (-8450 2725);
DISPLAY INVISIBLE (-8450 2725);
FORCEPROP 2 LAST CDS_LIB pure_quanta
J 2
(-8500 2550);
DISPLAY INVISIBLE (-8500 2550);
FORCEPROP 2 LAST ROOM 
J 0
(-8450 2775);
DISPLAY 0.808511 (-8450 2775);
PAINT RED (-8450 2775);
DISPLAY INVISIBLE (-8450 2775);
FORCEPROP 1 LAST PATH I190
J 0
(-8450 2725);
DISPLAY 0.978723 (-8450 2725);
PAINT WHITE (-8450 2725);
DISPLAY INVISIBLE (-8450 2725);
FORCEPROP 1 LAST PART_NUMBER CS21002FB06
J 0
(-8450 2525);
DISPLAY 0.489362 (-8450 2525);
PAINT SKYBLUE (-8450 2525);
DISPLAY INVISIBLE (-8450 2525);
FORCEADD TAP..1
(-3475 3875);
FORCEPROP 3 LASTPIN (-3525 3875) SIG_NAME M_E_CPU1_SA_DQS_DP<0>
J 0
(-3515 3885);
DISPLAY 0.659574 (-3515 3885);
PAINT MONO (-3515 3885);
DISPLAY INVISIBLE (-3515 3885);
FORCEPROP 1 LASTPIN (-3525 3875) BN 0
J 0
(-3537 3883);
DISPLAY 0.489362 (-3537 3883);
PAINT GREEN (-3537 3883);
FORCEPROP 2 LAST CDS_LIB mstr_standard
J 0
(-3475 3875);
DISPLAY 0.723404 (-3475 3875);
PAINT MONO (-3475 3875);
DISPLAY INVISIBLE (-3475 3875);
FORCEPROP 1 LAST BODY_TYPE PLUMBING
J 0
(-3475 3925);
DISPLAY 0.872340 (-3475 3925);
PAINT GREEN (-3475 3925);
DISPLAY INVISIBLE (-3475 3925);
FORCEPROP 1 LAST HDL_TAP TRUE
J 0
(-3150 3750);
DISPLAY 0.872340 (-3150 3750);
DISPLAY INVISIBLE (-3150 3750);
FORCEPROP 1 LAST PATH I192
J 0
(-3477 3875);
DISPLAY 0.872340 (-3477 3875);
PAINT GREEN (-3477 3875);
DISPLAY INVISIBLE (-3477 3875);
FORCEADD TAP..1
(-3275 4025);
FORCEPROP 3 LASTPIN (-3325 4025) SIG_NAME M_E_CPU1_SA_DQS_DN<2>
J 0
(-3315 4035);
DISPLAY 0.659574 (-3315 4035);
PAINT MONO (-3315 4035);
DISPLAY INVISIBLE (-3315 4035);
FORCEPROP 1 LASTPIN (-3325 4025) BN 2
J 0
(-3337 4033);
DISPLAY 0.489362 (-3337 4033);
PAINT GREEN (-3337 4033);
FORCEPROP 2 LAST CDS_LIB mstr_standard
J 0
(-3275 4025);
DISPLAY 0.723404 (-3275 4025);
PAINT MONO (-3275 4025);
DISPLAY INVISIBLE (-3275 4025);
FORCEPROP 1 LAST BODY_TYPE PLUMBING
J 0
(-3275 4075);
DISPLAY 0.872340 (-3275 4075);
PAINT GREEN (-3275 4075);
DISPLAY INVISIBLE (-3275 4075);
FORCEPROP 1 LAST HDL_TAP TRUE
J 0
(-2950 3900);
DISPLAY 0.872340 (-2950 3900);
DISPLAY INVISIBLE (-2950 3900);
FORCEPROP 1 LAST PATH I193
J 0
(-3277 4025);
DISPLAY 0.872340 (-3277 4025);
PAINT GREEN (-3277 4025);
DISPLAY INVISIBLE (-3277 4025);
FORCEADD OFFPAGE..2
(-2475 4825);
FORCEPROP 2 LAST $XR0 41 
J 0
(-2286 4825);
DISPLAY 0.638298 (-2286 4825);
PAINT MONO (-2286 4825);
FORCEPROP 2 LAST CDS_LIB mstr_standard
J 0
(-2475 4825);
DISPLAY 0.723404 (-2475 4825);
PAINT MONO (-2475 4825);
DISPLAY INVISIBLE (-2475 4825);
FORCEPROP 1 LAST OFFPAGE TRUE
J 0
(-2150 4700);
DISPLAY 0.723404 (-2150 4700);
PAINT GREEN (-2150 4700);
DISPLAY INVISIBLE (-2150 4700);
FORCEPROP 1 LAST COMMENT_BODY TRUE
J 0
(-2520 4730);
DISPLAY 0.872340 (-2520 4730);
PAINT GREEN (-2520 4730);
DISPLAY INVISIBLE (-2520 4730);
FORCEPROP 2 LAST PATH I194
J 0
(-2275 4875);
DISPLAY 0.680851 (-2275 4875);
DISPLAY INVISIBLE (-2275 4875);
FORCEADD OFFPAGE..2
(-2475 4775);
FORCEPROP 2 LAST $XR0 41 
J 0
(-2286 4775);
DISPLAY 0.638298 (-2286 4775);
PAINT MONO (-2286 4775);
FORCEPROP 2 LAST CDS_LIB mstr_standard
J 0
(-2475 4775);
DISPLAY 0.723404 (-2475 4775);
PAINT MONO (-2475 4775);
DISPLAY INVISIBLE (-2475 4775);
FORCEPROP 1 LAST OFFPAGE TRUE
J 0
(-2150 4650);
DISPLAY 0.723404 (-2150 4650);
PAINT GREEN (-2150 4650);
DISPLAY INVISIBLE (-2150 4650);
FORCEPROP 1 LAST COMMENT_BODY TRUE
J 0
(-2520 4680);
DISPLAY 0.872340 (-2520 4680);
PAINT GREEN (-2520 4680);
DISPLAY INVISIBLE (-2520 4680);
FORCEPROP 2 LAST PATH I195
J 0
(-2275 4825);
DISPLAY 0.680851 (-2275 4825);
DISPLAY INVISIBLE (-2275 4825);
FORCEADD OFFPAGE..2
(-2475 3775);
FORCEPROP 2 LAST $XR0 41 
J 0
(-2286 3775);
DISPLAY 0.638298 (-2286 3775);
PAINT MONO (-2286 3775);
FORCEPROP 2 LAST CDS_LIB mstr_standard
J 0
(-2475 3775);
DISPLAY 0.723404 (-2475 3775);
PAINT MONO (-2475 3775);
DISPLAY INVISIBLE (-2475 3775);
FORCEPROP 1 LAST OFFPAGE TRUE
J 0
(-2150 3650);
DISPLAY 0.723404 (-2150 3650);
PAINT GREEN (-2150 3650);
DISPLAY INVISIBLE (-2150 3650);
FORCEPROP 1 LAST COMMENT_BODY TRUE
J 0
(-2520 3680);
DISPLAY 0.872340 (-2520 3680);
PAINT GREEN (-2520 3680);
DISPLAY INVISIBLE (-2520 3680);
FORCEPROP 2 LAST PATH I196
J 0
(-2275 3825);
DISPLAY 0.680851 (-2275 3825);
DISPLAY INVISIBLE (-2275 3825);
FORCEADD OFFPAGE..2
(-2475 3725);
FORCEPROP 2 LAST $XR0 41 
J 0
(-2286 3725);
DISPLAY 0.638298 (-2286 3725);
PAINT MONO (-2286 3725);
FORCEPROP 2 LAST CDS_LIB mstr_standard
J 0
(-2475 3725);
DISPLAY 0.723404 (-2475 3725);
PAINT MONO (-2475 3725);
DISPLAY INVISIBLE (-2475 3725);
FORCEPROP 1 LAST OFFPAGE TRUE
J 0
(-2150 3600);
DISPLAY 0.723404 (-2150 3600);
PAINT GREEN (-2150 3600);
DISPLAY INVISIBLE (-2150 3600);
FORCEPROP 1 LAST COMMENT_BODY TRUE
J 0
(-2520 3630);
DISPLAY 0.872340 (-2520 3630);
PAINT GREEN (-2520 3630);
DISPLAY INVISIBLE (-2520 3630);
FORCEPROP 2 LAST PATH I197
J 0
(-2275 3775);
DISPLAY 0.680851 (-2275 3775);
DISPLAY INVISIBLE (-2275 3775);
FORCEADD TAP..1
(-3275 4625);
FORCEPROP 3 LASTPIN (-3325 4625) SIG_NAME M_E_CPU1_SA_DQS_DN<8>
J 0
(-3315 4635);
DISPLAY 0.659574 (-3315 4635);
PAINT MONO (-3315 4635);
DISPLAY INVISIBLE (-3315 4635);
FORCEPROP 1 LASTPIN (-3325 4625) BN 8
J 0
(-3337 4633);
DISPLAY 0.489362 (-3337 4633);
PAINT GREEN (-3337 4633);
FORCEPROP 2 LAST CDS_LIB mstr_standard
J 0
(-3275 4625);
DISPLAY 0.723404 (-3275 4625);
PAINT MONO (-3275 4625);
DISPLAY INVISIBLE (-3275 4625);
FORCEPROP 1 LAST BODY_TYPE PLUMBING
J 0
(-3275 4675);
DISPLAY 0.872340 (-3275 4675);
PAINT GREEN (-3275 4675);
DISPLAY INVISIBLE (-3275 4675);
FORCEPROP 1 LAST HDL_TAP TRUE
J 0
(-2950 4500);
DISPLAY 0.872340 (-2950 4500);
DISPLAY INVISIBLE (-2950 4500);
FORCEPROP 1 LAST PATH I198
J 0
(-3277 4625);
DISPLAY 0.872340 (-3277 4625);
PAINT GREEN (-3277 4625);
DISPLAY INVISIBLE (-3277 4625);
FORCEADD TAP..1
(-3275 4725);
FORCEPROP 3 LASTPIN (-3325 4725) SIG_NAME M_E_CPU1_SA_DQS_DN<9>
J 0
(-3315 4735);
DISPLAY 0.659574 (-3315 4735);
PAINT MONO (-3315 4735);
DISPLAY INVISIBLE (-3315 4735);
FORCEPROP 1 LASTPIN (-3325 4725) BN 9
J 0
(-3337 4733);
DISPLAY 0.489362 (-3337 4733);
PAINT GREEN (-3337 4733);
FORCEPROP 2 LAST CDS_LIB mstr_standard
J 0
(-3275 4725);
DISPLAY 0.723404 (-3275 4725);
PAINT MONO (-3275 4725);
DISPLAY INVISIBLE (-3275 4725);
FORCEPROP 1 LAST BODY_TYPE PLUMBING
J 0
(-3275 4775);
DISPLAY 0.872340 (-3275 4775);
PAINT GREEN (-3275 4775);
DISPLAY INVISIBLE (-3275 4775);
FORCEPROP 1 LAST HDL_TAP TRUE
J 0
(-2950 4600);
DISPLAY 0.872340 (-2950 4600);
DISPLAY INVISIBLE (-2950 4600);
FORCEPROP 1 LAST PATH I199
J 0
(-3277 4725);
DISPLAY 0.872340 (-3277 4725);
PAINT GREEN (-3277 4725);
DISPLAY INVISIBLE (-3277 4725);
FORCEADD OFFPAGE..5
(-8475 2250);
FORCEPROP 2 LAST $XR0 41 
J 0
(-8699 2250);
DISPLAY 0.638298 (-8699 2250);
PAINT MONO (-8699 2250);
FORCEPROP 2 LAST CDS_LIB mstr_standard
J 0
(-8475 2250);
DISPLAY 0.808511 (-8475 2250);
DISPLAY INVISIBLE (-8475 2250);
FORCEPROP 1 LAST OFFPAGE TRUE
J 0
(-8150 2125);
DISPLAY 0.872340 (-8150 2125);
PAINT GREEN (-8150 2125);
DISPLAY INVISIBLE (-8150 2125);
FORCEPROP 1 LAST COMMENT_BODY TRUE
J 0
(-8375 2175);
DISPLAY 0.872340 (-8375 2175);
PAINT GREEN (-8375 2175);
DISPLAY INVISIBLE (-8375 2175);
FORCEPROP 2 LAST PATH I2
J 0
(-8725 2300);
DISPLAY 1.021277 (-8725 2300);
DISPLAY INVISIBLE (-8725 2300);
FORCEADD TAP..1
R 2
(-7875 4000);
FORCEPROP 3 LASTPIN (-7825 4000) SIG_NAME M_E_CPU1_SA_CB<2>
J 0
(-7815 4010);
DISPLAY 0.659574 (-7815 4010);
PAINT MONO (-7815 4010);
DISPLAY INVISIBLE (-7815 4010);
FORCEPROP 1 LASTPIN (-7825 4000) BN 2
J 2
(-7813 4008);
DISPLAY 0.489362 (-7813 4008);
PAINT GREEN (-7813 4008);
FORCEPROP 2 LAST CDS_LIB mstr_standard
J 0
(-7875 4000);
DISPLAY 0.723404 (-7875 4000);
PAINT MONO (-7875 4000);
DISPLAY INVISIBLE (-7875 4000);
FORCEPROP 1 LAST BODY_TYPE PLUMBING
J 2
(-7875 4050);
DISPLAY 0.872340 (-7875 4050);
PAINT GREEN (-7875 4050);
DISPLAY INVISIBLE (-7875 4050);
FORCEPROP 1 LAST HDL_TAP TRUE
J 2
(-8200 3875);
DISPLAY 0.872340 (-8200 3875);
DISPLAY INVISIBLE (-8200 3875);
FORCEPROP 1 LAST PATH I20
J 2
(-7873 4000);
DISPLAY 0.872340 (-7873 4000);
PAINT GREEN (-7873 4000);
DISPLAY INVISIBLE (-7873 4000);
FORCEADD TAP..1
(-3275 4425);
FORCEPROP 3 LASTPIN (-3325 4425) SIG_NAME M_E_CPU1_SA_DQS_DN<6>
J 0
(-3315 4435);
DISPLAY 0.659574 (-3315 4435);
PAINT MONO (-3315 4435);
DISPLAY INVISIBLE (-3315 4435);
FORCEPROP 1 LASTPIN (-3325 4425) BN 6
J 0
(-3337 4433);
DISPLAY 0.489362 (-3337 4433);
PAINT GREEN (-3337 4433);
FORCEPROP 2 LAST CDS_LIB mstr_standard
J 0
(-3275 4425);
DISPLAY 0.723404 (-3275 4425);
PAINT MONO (-3275 4425);
DISPLAY INVISIBLE (-3275 4425);
FORCEPROP 1 LAST BODY_TYPE PLUMBING
J 0
(-3275 4475);
DISPLAY 0.872340 (-3275 4475);
PAINT GREEN (-3275 4475);
DISPLAY INVISIBLE (-3275 4475);
FORCEPROP 1 LAST HDL_TAP TRUE
J 0
(-2950 4300);
DISPLAY 0.872340 (-2950 4300);
DISPLAY INVISIBLE (-2950 4300);
FORCEPROP 1 LAST PATH I200
J 0
(-3277 4425);
DISPLAY 0.872340 (-3277 4425);
PAINT GREEN (-3277 4425);
DISPLAY INVISIBLE (-3277 4425);
FORCEADD TAP..1
(-3275 4525);
FORCEPROP 3 LASTPIN (-3325 4525) SIG_NAME M_E_CPU1_SA_DQS_DN<7>
J 0
(-3315 4535);
DISPLAY 0.659574 (-3315 4535);
PAINT MONO (-3315 4535);
DISPLAY INVISIBLE (-3315 4535);
FORCEPROP 1 LASTPIN (-3325 4525) BN 7
J 0
(-3337 4533);
DISPLAY 0.489362 (-3337 4533);
PAINT GREEN (-3337 4533);
FORCEPROP 2 LAST CDS_LIB mstr_standard
J 0
(-3275 4525);
DISPLAY 0.723404 (-3275 4525);
PAINT MONO (-3275 4525);
DISPLAY INVISIBLE (-3275 4525);
FORCEPROP 1 LAST BODY_TYPE PLUMBING
J 0
(-3275 4575);
DISPLAY 0.872340 (-3275 4575);
PAINT GREEN (-3275 4575);
DISPLAY INVISIBLE (-3275 4575);
FORCEPROP 1 LAST HDL_TAP TRUE
J 0
(-2950 4400);
DISPLAY 0.872340 (-2950 4400);
DISPLAY INVISIBLE (-2950 4400);
FORCEPROP 1 LAST PATH I201
J 0
(-3277 4525);
DISPLAY 0.872340 (-3277 4525);
PAINT GREEN (-3277 4525);
DISPLAY INVISIBLE (-3277 4525);
FORCEADD TAP..1
(-3275 4325);
FORCEPROP 3 LASTPIN (-3325 4325) SIG_NAME M_E_CPU1_SA_DQS_DN<5>
J 0
(-3315 4335);
DISPLAY 0.659574 (-3315 4335);
PAINT MONO (-3315 4335);
DISPLAY INVISIBLE (-3315 4335);
FORCEPROP 1 LASTPIN (-3325 4325) BN 5
J 0
(-3337 4333);
DISPLAY 0.489362 (-3337 4333);
PAINT GREEN (-3337 4333);
FORCEPROP 2 LAST CDS_LIB mstr_standard
J 0
(-3275 4325);
DISPLAY 0.723404 (-3275 4325);
PAINT MONO (-3275 4325);
DISPLAY INVISIBLE (-3275 4325);
FORCEPROP 1 LAST BODY_TYPE PLUMBING
J 0
(-3275 4375);
DISPLAY 0.872340 (-3275 4375);
PAINT GREEN (-3275 4375);
DISPLAY INVISIBLE (-3275 4375);
FORCEPROP 1 LAST HDL_TAP TRUE
J 0
(-2950 4200);
DISPLAY 0.872340 (-2950 4200);
DISPLAY INVISIBLE (-2950 4200);
FORCEPROP 1 LAST PATH I202
J 0
(-3277 4325);
DISPLAY 0.872340 (-3277 4325);
PAINT GREEN (-3277 4325);
DISPLAY INVISIBLE (-3277 4325);
FORCEADD TAP..1
(-3475 4775);
FORCEPROP 3 LASTPIN (-3525 4775) SIG_NAME M_E_CPU1_SA_DQS_DP<9>
J 0
(-3515 4785);
DISPLAY 0.659574 (-3515 4785);
PAINT MONO (-3515 4785);
DISPLAY INVISIBLE (-3515 4785);
FORCEPROP 1 LASTPIN (-3525 4775) BN 9
J 0
(-3537 4783);
DISPLAY 0.489362 (-3537 4783);
PAINT GREEN (-3537 4783);
FORCEPROP 2 LAST CDS_LIB mstr_standard
J 0
(-3475 4775);
DISPLAY 0.723404 (-3475 4775);
PAINT MONO (-3475 4775);
DISPLAY INVISIBLE (-3475 4775);
FORCEPROP 1 LAST BODY_TYPE PLUMBING
J 0
(-3475 4825);
DISPLAY 0.872340 (-3475 4825);
PAINT GREEN (-3475 4825);
DISPLAY INVISIBLE (-3475 4825);
FORCEPROP 1 LAST HDL_TAP TRUE
J 0
(-3150 4650);
DISPLAY 0.872340 (-3150 4650);
DISPLAY INVISIBLE (-3150 4650);
FORCEPROP 1 LAST PATH I203
J 0
(-3477 4775);
DISPLAY 0.872340 (-3477 4775);
PAINT GREEN (-3477 4775);
DISPLAY INVISIBLE (-3477 4775);
FORCEADD TAP..1
(-3475 4675);
FORCEPROP 3 LASTPIN (-3525 4675) SIG_NAME M_E_CPU1_SA_DQS_DP<8>
J 0
(-3515 4685);
DISPLAY 0.659574 (-3515 4685);
PAINT MONO (-3515 4685);
DISPLAY INVISIBLE (-3515 4685);
FORCEPROP 1 LASTPIN (-3525 4675) BN 8
J 0
(-3537 4683);
DISPLAY 0.489362 (-3537 4683);
PAINT GREEN (-3537 4683);
FORCEPROP 2 LAST CDS_LIB mstr_standard
J 0
(-3475 4675);
DISPLAY 0.723404 (-3475 4675);
PAINT MONO (-3475 4675);
DISPLAY INVISIBLE (-3475 4675);
FORCEPROP 1 LAST BODY_TYPE PLUMBING
J 0
(-3475 4725);
DISPLAY 0.872340 (-3475 4725);
PAINT GREEN (-3475 4725);
DISPLAY INVISIBLE (-3475 4725);
FORCEPROP 1 LAST HDL_TAP TRUE
J 0
(-3150 4550);
DISPLAY 0.872340 (-3150 4550);
DISPLAY INVISIBLE (-3150 4550);
FORCEPROP 1 LAST PATH I204
J 0
(-3477 4675);
DISPLAY 0.872340 (-3477 4675);
PAINT GREEN (-3477 4675);
DISPLAY INVISIBLE (-3477 4675);
FORCEADD TAP..1
(-3475 4575);
FORCEPROP 3 LASTPIN (-3525 4575) SIG_NAME M_E_CPU1_SA_DQS_DP<7>
J 0
(-3515 4585);
DISPLAY 0.659574 (-3515 4585);
PAINT MONO (-3515 4585);
DISPLAY INVISIBLE (-3515 4585);
FORCEPROP 1 LASTPIN (-3525 4575) BN 7
J 0
(-3537 4583);
DISPLAY 0.489362 (-3537 4583);
PAINT GREEN (-3537 4583);
FORCEPROP 2 LAST CDS_LIB mstr_standard
J 0
(-3475 4575);
DISPLAY 0.723404 (-3475 4575);
PAINT MONO (-3475 4575);
DISPLAY INVISIBLE (-3475 4575);
FORCEPROP 1 LAST BODY_TYPE PLUMBING
J 0
(-3475 4625);
DISPLAY 0.872340 (-3475 4625);
PAINT GREEN (-3475 4625);
DISPLAY INVISIBLE (-3475 4625);
FORCEPROP 1 LAST HDL_TAP TRUE
J 0
(-3150 4450);
DISPLAY 0.872340 (-3150 4450);
DISPLAY INVISIBLE (-3150 4450);
FORCEPROP 1 LAST PATH I205
J 0
(-3477 4575);
DISPLAY 0.872340 (-3477 4575);
PAINT GREEN (-3477 4575);
DISPLAY INVISIBLE (-3477 4575);
FORCEADD TAP..1
(-3475 4475);
FORCEPROP 3 LASTPIN (-3525 4475) SIG_NAME M_E_CPU1_SA_DQS_DP<6>
J 0
(-3515 4485);
DISPLAY 0.659574 (-3515 4485);
PAINT MONO (-3515 4485);
DISPLAY INVISIBLE (-3515 4485);
FORCEPROP 1 LASTPIN (-3525 4475) BN 6
J 0
(-3537 4483);
DISPLAY 0.489362 (-3537 4483);
PAINT GREEN (-3537 4483);
FORCEPROP 2 LAST CDS_LIB mstr_standard
J 0
(-3475 4475);
DISPLAY 0.723404 (-3475 4475);
PAINT MONO (-3475 4475);
DISPLAY INVISIBLE (-3475 4475);
FORCEPROP 1 LAST BODY_TYPE PLUMBING
J 0
(-3475 4525);
DISPLAY 0.872340 (-3475 4525);
PAINT GREEN (-3475 4525);
DISPLAY INVISIBLE (-3475 4525);
FORCEPROP 1 LAST HDL_TAP TRUE
J 0
(-3150 4350);
DISPLAY 0.872340 (-3150 4350);
DISPLAY INVISIBLE (-3150 4350);
FORCEPROP 1 LAST PATH I206
J 0
(-3477 4475);
DISPLAY 0.872340 (-3477 4475);
PAINT GREEN (-3477 4475);
DISPLAY INVISIBLE (-3477 4475);
FORCEADD TAP..1
(-3475 4375);
FORCEPROP 3 LASTPIN (-3525 4375) SIG_NAME M_E_CPU1_SA_DQS_DP<5>
J 0
(-3515 4385);
DISPLAY 0.659574 (-3515 4385);
PAINT MONO (-3515 4385);
DISPLAY INVISIBLE (-3515 4385);
FORCEPROP 1 LASTPIN (-3525 4375) BN 5
J 0
(-3537 4383);
DISPLAY 0.489362 (-3537 4383);
PAINT GREEN (-3537 4383);
FORCEPROP 2 LAST CDS_LIB mstr_standard
J 0
(-3475 4375);
DISPLAY 0.723404 (-3475 4375);
PAINT MONO (-3475 4375);
DISPLAY INVISIBLE (-3475 4375);
FORCEPROP 1 LAST BODY_TYPE PLUMBING
J 0
(-3475 4425);
DISPLAY 0.872340 (-3475 4425);
PAINT GREEN (-3475 4425);
DISPLAY INVISIBLE (-3475 4425);
FORCEPROP 1 LAST HDL_TAP TRUE
J 0
(-3150 4250);
DISPLAY 0.872340 (-3150 4250);
DISPLAY INVISIBLE (-3150 4250);
FORCEPROP 1 LAST PATH I207
J 0
(-3477 4375);
DISPLAY 0.872340 (-3477 4375);
PAINT GREEN (-3477 4375);
DISPLAY INVISIBLE (-3477 4375);
FORCEADD TAP..1
(-3275 4225);
FORCEPROP 3 LASTPIN (-3325 4225) SIG_NAME M_E_CPU1_SA_DQS_DN<4>
J 0
(-3315 4235);
DISPLAY 0.659574 (-3315 4235);
PAINT MONO (-3315 4235);
DISPLAY INVISIBLE (-3315 4235);
FORCEPROP 1 LASTPIN (-3325 4225) BN 4
J 0
(-3337 4233);
DISPLAY 0.489362 (-3337 4233);
PAINT GREEN (-3337 4233);
FORCEPROP 2 LAST CDS_LIB mstr_standard
J 0
(-3275 4225);
DISPLAY 0.723404 (-3275 4225);
PAINT MONO (-3275 4225);
DISPLAY INVISIBLE (-3275 4225);
FORCEPROP 1 LAST BODY_TYPE PLUMBING
J 0
(-3275 4275);
DISPLAY 0.872340 (-3275 4275);
PAINT GREEN (-3275 4275);
DISPLAY INVISIBLE (-3275 4275);
FORCEPROP 1 LAST HDL_TAP TRUE
J 0
(-2950 4100);
DISPLAY 0.872340 (-2950 4100);
DISPLAY INVISIBLE (-2950 4100);
FORCEPROP 1 LAST PATH I208
J 0
(-3277 4225);
DISPLAY 0.872340 (-3277 4225);
PAINT GREEN (-3277 4225);
DISPLAY INVISIBLE (-3277 4225);
FORCEADD TAP..1
(-3275 4125);
FORCEPROP 3 LASTPIN (-3325 4125) SIG_NAME M_E_CPU1_SA_DQS_DN<3>
J 0
(-3315 4135);
DISPLAY 0.659574 (-3315 4135);
PAINT MONO (-3315 4135);
DISPLAY INVISIBLE (-3315 4135);
FORCEPROP 1 LASTPIN (-3325 4125) BN 3
J 0
(-3337 4133);
DISPLAY 0.489362 (-3337 4133);
PAINT GREEN (-3337 4133);
FORCEPROP 2 LAST CDS_LIB mstr_standard
J 0
(-3275 4125);
DISPLAY 0.723404 (-3275 4125);
PAINT MONO (-3275 4125);
DISPLAY INVISIBLE (-3275 4125);
FORCEPROP 1 LAST BODY_TYPE PLUMBING
J 0
(-3275 4175);
DISPLAY 0.872340 (-3275 4175);
PAINT GREEN (-3275 4175);
DISPLAY INVISIBLE (-3275 4175);
FORCEPROP 1 LAST HDL_TAP TRUE
J 0
(-2950 4000);
DISPLAY 0.872340 (-2950 4000);
DISPLAY INVISIBLE (-2950 4000);
FORCEPROP 1 LAST PATH I209
J 0
(-3277 4125);
DISPLAY 0.872340 (-3277 4125);
PAINT GREEN (-3277 4125);
DISPLAY INVISIBLE (-3277 4125);
FORCEADD TAP..1
R 2
(-7875 3950);
FORCEPROP 3 LASTPIN (-7825 3950) SIG_NAME M_E_CPU1_SA_CB<1>
J 0
(-7815 3960);
DISPLAY 0.659574 (-7815 3960);
PAINT MONO (-7815 3960);
DISPLAY INVISIBLE (-7815 3960);
FORCEPROP 1 LASTPIN (-7825 3950) BN 1
J 2
(-7813 3958);
DISPLAY 0.489362 (-7813 3958);
PAINT GREEN (-7813 3958);
FORCEPROP 2 LAST CDS_LIB mstr_standard
J 0
(-7875 3950);
DISPLAY 0.723404 (-7875 3950);
PAINT MONO (-7875 3950);
DISPLAY INVISIBLE (-7875 3950);
FORCEPROP 1 LAST BODY_TYPE PLUMBING
J 2
(-7875 4000);
DISPLAY 0.872340 (-7875 4000);
PAINT GREEN (-7875 4000);
DISPLAY INVISIBLE (-7875 4000);
FORCEPROP 1 LAST HDL_TAP TRUE
J 2
(-8200 3825);
DISPLAY 0.872340 (-8200 3825);
DISPLAY INVISIBLE (-8200 3825);
FORCEPROP 1 LAST PATH I21
J 2
(-7873 3950);
DISPLAY 0.872340 (-7873 3950);
PAINT GREEN (-7873 3950);
DISPLAY INVISIBLE (-7873 3950);
FORCEADD TAP..1
(-3275 3925);
FORCEPROP 3 LASTPIN (-3325 3925) SIG_NAME M_E_CPU1_SA_DQS_DN<1>
J 0
(-3315 3935);
DISPLAY 0.659574 (-3315 3935);
PAINT MONO (-3315 3935);
DISPLAY INVISIBLE (-3315 3935);
FORCEPROP 1 LASTPIN (-3325 3925) BN 1
J 0
(-3337 3933);
DISPLAY 0.489362 (-3337 3933);
PAINT GREEN (-3337 3933);
FORCEPROP 2 LAST CDS_LIB mstr_standard
J 0
(-3275 3925);
DISPLAY 0.723404 (-3275 3925);
PAINT MONO (-3275 3925);
DISPLAY INVISIBLE (-3275 3925);
FORCEPROP 1 LAST BODY_TYPE PLUMBING
J 0
(-3275 3975);
DISPLAY 0.872340 (-3275 3975);
PAINT GREEN (-3275 3975);
DISPLAY INVISIBLE (-3275 3975);
FORCEPROP 1 LAST HDL_TAP TRUE
J 0
(-2950 3800);
DISPLAY 0.872340 (-2950 3800);
DISPLAY INVISIBLE (-2950 3800);
FORCEPROP 1 LAST PATH I210
J 0
(-3277 3925);
DISPLAY 0.872340 (-3277 3925);
PAINT GREEN (-3277 3925);
DISPLAY INVISIBLE (-3277 3925);
FORCEADD TAP..1
(-3275 3825);
FORCEPROP 3 LASTPIN (-3325 3825) SIG_NAME M_E_CPU1_SA_DQS_DN<0>
J 0
(-3315 3835);
DISPLAY 0.659574 (-3315 3835);
PAINT MONO (-3315 3835);
DISPLAY INVISIBLE (-3315 3835);
FORCEPROP 1 LASTPIN (-3325 3825) BN 0
J 0
(-3337 3833);
DISPLAY 0.489362 (-3337 3833);
PAINT GREEN (-3337 3833);
FORCEPROP 2 LAST CDS_LIB mstr_standard
J 0
(-3275 3825);
DISPLAY 0.723404 (-3275 3825);
PAINT MONO (-3275 3825);
DISPLAY INVISIBLE (-3275 3825);
FORCEPROP 1 LAST BODY_TYPE PLUMBING
J 0
(-3275 3875);
DISPLAY 0.872340 (-3275 3875);
PAINT GREEN (-3275 3875);
DISPLAY INVISIBLE (-3275 3875);
FORCEPROP 1 LAST HDL_TAP TRUE
J 0
(-2950 3700);
DISPLAY 0.872340 (-2950 3700);
DISPLAY INVISIBLE (-2950 3700);
FORCEPROP 1 LAST PATH I211
J 0
(-3277 3825);
DISPLAY 0.872340 (-3277 3825);
PAINT GREEN (-3277 3825);
DISPLAY INVISIBLE (-3277 3825);
FORCEADD TAP..1
(-3475 4275);
FORCEPROP 3 LASTPIN (-3525 4275) SIG_NAME M_E_CPU1_SA_DQS_DP<4>
J 0
(-3515 4285);
DISPLAY 0.659574 (-3515 4285);
PAINT MONO (-3515 4285);
DISPLAY INVISIBLE (-3515 4285);
FORCEPROP 1 LASTPIN (-3525 4275) BN 4
J 0
(-3537 4283);
DISPLAY 0.489362 (-3537 4283);
PAINT GREEN (-3537 4283);
FORCEPROP 2 LAST CDS_LIB mstr_standard
J 0
(-3475 4275);
DISPLAY 0.723404 (-3475 4275);
PAINT MONO (-3475 4275);
DISPLAY INVISIBLE (-3475 4275);
FORCEPROP 1 LAST BODY_TYPE PLUMBING
J 0
(-3475 4325);
DISPLAY 0.872340 (-3475 4325);
PAINT GREEN (-3475 4325);
DISPLAY INVISIBLE (-3475 4325);
FORCEPROP 1 LAST HDL_TAP TRUE
J 0
(-3150 4150);
DISPLAY 0.872340 (-3150 4150);
DISPLAY INVISIBLE (-3150 4150);
FORCEPROP 1 LAST PATH I212
J 0
(-3477 4275);
DISPLAY 0.872340 (-3477 4275);
PAINT GREEN (-3477 4275);
DISPLAY INVISIBLE (-3477 4275);
FORCEADD TAP..1
(-3475 4175);
FORCEPROP 3 LASTPIN (-3525 4175) SIG_NAME M_E_CPU1_SA_DQS_DP<3>
J 0
(-3515 4185);
DISPLAY 0.659574 (-3515 4185);
PAINT MONO (-3515 4185);
DISPLAY INVISIBLE (-3515 4185);
FORCEPROP 1 LASTPIN (-3525 4175) BN 3
J 0
(-3537 4183);
DISPLAY 0.489362 (-3537 4183);
PAINT GREEN (-3537 4183);
FORCEPROP 2 LAST CDS_LIB mstr_standard
J 0
(-3475 4175);
DISPLAY 0.723404 (-3475 4175);
PAINT MONO (-3475 4175);
DISPLAY INVISIBLE (-3475 4175);
FORCEPROP 1 LAST BODY_TYPE PLUMBING
J 0
(-3475 4225);
DISPLAY 0.872340 (-3475 4225);
PAINT GREEN (-3475 4225);
DISPLAY INVISIBLE (-3475 4225);
FORCEPROP 1 LAST HDL_TAP TRUE
J 0
(-3150 4050);
DISPLAY 0.872340 (-3150 4050);
DISPLAY INVISIBLE (-3150 4050);
FORCEPROP 1 LAST PATH I213
J 0
(-3477 4175);
DISPLAY 0.872340 (-3477 4175);
PAINT GREEN (-3477 4175);
DISPLAY INVISIBLE (-3477 4175);
FORCEADD TAP..1
(-3475 4075);
FORCEPROP 3 LASTPIN (-3525 4075) SIG_NAME M_E_CPU1_SA_DQS_DP<2>
J 0
(-3515 4085);
DISPLAY 0.659574 (-3515 4085);
PAINT MONO (-3515 4085);
DISPLAY INVISIBLE (-3515 4085);
FORCEPROP 1 LASTPIN (-3525 4075) BN 2
J 0
(-3537 4083);
DISPLAY 0.489362 (-3537 4083);
PAINT GREEN (-3537 4083);
FORCEPROP 2 LAST CDS_LIB mstr_standard
J 0
(-3475 4075);
DISPLAY 0.723404 (-3475 4075);
PAINT MONO (-3475 4075);
DISPLAY INVISIBLE (-3475 4075);
FORCEPROP 1 LAST BODY_TYPE PLUMBING
J 0
(-3475 4125);
DISPLAY 0.872340 (-3475 4125);
PAINT GREEN (-3475 4125);
DISPLAY INVISIBLE (-3475 4125);
FORCEPROP 1 LAST HDL_TAP TRUE
J 0
(-3150 3950);
DISPLAY 0.872340 (-3150 3950);
DISPLAY INVISIBLE (-3150 3950);
FORCEPROP 1 LAST PATH I214
J 0
(-3477 4075);
DISPLAY 0.872340 (-3477 4075);
PAINT GREEN (-3477 4075);
DISPLAY INVISIBLE (-3477 4075);
FORCEADD TAP..1
(-3475 3975);
FORCEPROP 3 LASTPIN (-3525 3975) SIG_NAME M_E_CPU1_SA_DQS_DP<1>
J 0
(-3515 3985);
DISPLAY 0.659574 (-3515 3985);
PAINT MONO (-3515 3985);
DISPLAY INVISIBLE (-3515 3985);
FORCEPROP 1 LASTPIN (-3525 3975) BN 1
J 0
(-3537 3983);
DISPLAY 0.489362 (-3537 3983);
PAINT GREEN (-3537 3983);
FORCEPROP 2 LAST CDS_LIB mstr_standard
J 0
(-3475 3975);
DISPLAY 0.723404 (-3475 3975);
PAINT MONO (-3475 3975);
DISPLAY INVISIBLE (-3475 3975);
FORCEPROP 1 LAST BODY_TYPE PLUMBING
J 0
(-3475 4025);
DISPLAY 0.872340 (-3475 4025);
PAINT GREEN (-3475 4025);
DISPLAY INVISIBLE (-3475 4025);
FORCEPROP 1 LAST HDL_TAP TRUE
J 0
(-3150 3850);
DISPLAY 0.872340 (-3150 3850);
DISPLAY INVISIBLE (-3150 3850);
FORCEPROP 1 LAST PATH I215
J 0
(-3477 3975);
DISPLAY 0.872340 (-3477 3975);
PAINT GREEN (-3477 3975);
DISPLAY INVISIBLE (-3477 3975);
FORCEADD TAP..1
(-3275 3575);
FORCEPROP 3 LASTPIN (-3325 3575) SIG_NAME M_E_CPU1_SB_DQS_DN<8>
J 0
(-3315 3585);
DISPLAY 0.659574 (-3315 3585);
PAINT MONO (-3315 3585);
DISPLAY INVISIBLE (-3315 3585);
FORCEPROP 1 LASTPIN (-3325 3575) BN 8
J 0
(-3337 3583);
DISPLAY 0.489362 (-3337 3583);
PAINT GREEN (-3337 3583);
FORCEPROP 2 LAST CDS_LIB mstr_standard
J 0
(-3275 3575);
DISPLAY 0.723404 (-3275 3575);
PAINT MONO (-3275 3575);
DISPLAY INVISIBLE (-3275 3575);
FORCEPROP 1 LAST BODY_TYPE PLUMBING
J 0
(-3275 3625);
DISPLAY 0.872340 (-3275 3625);
PAINT GREEN (-3275 3625);
DISPLAY INVISIBLE (-3275 3625);
FORCEPROP 1 LAST HDL_TAP TRUE
J 0
(-2950 3450);
DISPLAY 0.872340 (-2950 3450);
DISPLAY INVISIBLE (-2950 3450);
FORCEPROP 1 LAST PATH I216
J 0
(-3277 3575);
DISPLAY 0.872340 (-3277 3575);
PAINT GREEN (-3277 3575);
DISPLAY INVISIBLE (-3277 3575);
FORCEADD TAP..1
(-3275 3675);
FORCEPROP 3 LASTPIN (-3325 3675) SIG_NAME M_E_CPU1_SB_DQS_DN<9>
J 0
(-3315 3685);
DISPLAY 0.659574 (-3315 3685);
PAINT MONO (-3315 3685);
DISPLAY INVISIBLE (-3315 3685);
FORCEPROP 1 LASTPIN (-3325 3675) BN 9
J 0
(-3337 3683);
DISPLAY 0.489362 (-3337 3683);
PAINT GREEN (-3337 3683);
FORCEPROP 2 LAST CDS_LIB mstr_standard
J 0
(-3275 3675);
DISPLAY 0.723404 (-3275 3675);
PAINT MONO (-3275 3675);
DISPLAY INVISIBLE (-3275 3675);
FORCEPROP 1 LAST BODY_TYPE PLUMBING
J 0
(-3275 3725);
DISPLAY 0.872340 (-3275 3725);
PAINT GREEN (-3275 3725);
DISPLAY INVISIBLE (-3275 3725);
FORCEPROP 1 LAST HDL_TAP TRUE
J 0
(-2950 3550);
DISPLAY 0.872340 (-2950 3550);
DISPLAY INVISIBLE (-2950 3550);
FORCEPROP 1 LAST PATH I217
J 0
(-3277 3675);
DISPLAY 0.872340 (-3277 3675);
PAINT GREEN (-3277 3675);
DISPLAY INVISIBLE (-3277 3675);
FORCEADD TAP..1
(-3275 3375);
FORCEPROP 3 LASTPIN (-3325 3375) SIG_NAME M_E_CPU1_SB_DQS_DN<6>
J 0
(-3315 3385);
DISPLAY 0.659574 (-3315 3385);
PAINT MONO (-3315 3385);
DISPLAY INVISIBLE (-3315 3385);
FORCEPROP 1 LASTPIN (-3325 3375) BN 6
J 0
(-3337 3383);
DISPLAY 0.489362 (-3337 3383);
PAINT GREEN (-3337 3383);
FORCEPROP 2 LAST CDS_LIB mstr_standard
J 0
(-3275 3375);
DISPLAY 0.723404 (-3275 3375);
PAINT MONO (-3275 3375);
DISPLAY INVISIBLE (-3275 3375);
FORCEPROP 1 LAST BODY_TYPE PLUMBING
J 0
(-3275 3425);
DISPLAY 0.872340 (-3275 3425);
PAINT GREEN (-3275 3425);
DISPLAY INVISIBLE (-3275 3425);
FORCEPROP 1 LAST HDL_TAP TRUE
J 0
(-2950 3250);
DISPLAY 0.872340 (-2950 3250);
DISPLAY INVISIBLE (-2950 3250);
FORCEPROP 1 LAST PATH I218
J 0
(-3277 3375);
DISPLAY 0.872340 (-3277 3375);
PAINT GREEN (-3277 3375);
DISPLAY INVISIBLE (-3277 3375);
FORCEADD TAP..1
(-3275 3475);
FORCEPROP 3 LASTPIN (-3325 3475) SIG_NAME M_E_CPU1_SB_DQS_DN<7>
J 0
(-3315 3485);
DISPLAY 0.659574 (-3315 3485);
PAINT MONO (-3315 3485);
DISPLAY INVISIBLE (-3315 3485);
FORCEPROP 1 LASTPIN (-3325 3475) BN 7
J 0
(-3337 3483);
DISPLAY 0.489362 (-3337 3483);
PAINT GREEN (-3337 3483);
FORCEPROP 2 LAST CDS_LIB mstr_standard
J 0
(-3275 3475);
DISPLAY 0.723404 (-3275 3475);
PAINT MONO (-3275 3475);
DISPLAY INVISIBLE (-3275 3475);
FORCEPROP 1 LAST BODY_TYPE PLUMBING
J 0
(-3275 3525);
DISPLAY 0.872340 (-3275 3525);
PAINT GREEN (-3275 3525);
DISPLAY INVISIBLE (-3275 3525);
FORCEPROP 1 LAST HDL_TAP TRUE
J 0
(-2950 3350);
DISPLAY 0.872340 (-2950 3350);
DISPLAY INVISIBLE (-2950 3350);
FORCEPROP 1 LAST PATH I219
J 0
(-3277 3475);
DISPLAY 0.872340 (-3277 3475);
PAINT GREEN (-3277 3475);
DISPLAY INVISIBLE (-3277 3475);
FORCEADD TAP..1
R 2
(-7875 4050);
FORCEPROP 3 LASTPIN (-7825 4050) SIG_NAME M_E_CPU1_SA_CB<3>
J 0
(-7815 4060);
DISPLAY 0.659574 (-7815 4060);
PAINT MONO (-7815 4060);
DISPLAY INVISIBLE (-7815 4060);
FORCEPROP 1 LASTPIN (-7825 4050) BN 3
J 2
(-7813 4058);
DISPLAY 0.489362 (-7813 4058);
PAINT GREEN (-7813 4058);
FORCEPROP 2 LAST CDS_LIB mstr_standard
J 0
(-7875 4050);
DISPLAY 0.723404 (-7875 4050);
PAINT MONO (-7875 4050);
DISPLAY INVISIBLE (-7875 4050);
FORCEPROP 1 LAST BODY_TYPE PLUMBING
J 2
(-7875 4100);
DISPLAY 0.872340 (-7875 4100);
PAINT GREEN (-7875 4100);
DISPLAY INVISIBLE (-7875 4100);
FORCEPROP 1 LAST HDL_TAP TRUE
J 2
(-8200 3925);
DISPLAY 0.872340 (-8200 3925);
DISPLAY INVISIBLE (-8200 3925);
FORCEPROP 1 LAST PATH I22
J 2
(-7873 4050);
DISPLAY 0.872340 (-7873 4050);
PAINT GREEN (-7873 4050);
DISPLAY INVISIBLE (-7873 4050);
FORCEADD TAP..1
(-3475 3725);
FORCEPROP 3 LASTPIN (-3525 3725) SIG_NAME M_E_CPU1_SB_DQS_DP<9>
J 0
(-3515 3735);
DISPLAY 0.659574 (-3515 3735);
PAINT MONO (-3515 3735);
DISPLAY INVISIBLE (-3515 3735);
FORCEPROP 1 LASTPIN (-3525 3725) BN 9
J 0
(-3537 3733);
DISPLAY 0.489362 (-3537 3733);
PAINT GREEN (-3537 3733);
FORCEPROP 2 LAST CDS_LIB mstr_standard
J 0
(-3475 3725);
DISPLAY 0.723404 (-3475 3725);
PAINT MONO (-3475 3725);
DISPLAY INVISIBLE (-3475 3725);
FORCEPROP 1 LAST BODY_TYPE PLUMBING
J 0
(-3475 3775);
DISPLAY 0.872340 (-3475 3775);
PAINT GREEN (-3475 3775);
DISPLAY INVISIBLE (-3475 3775);
FORCEPROP 1 LAST HDL_TAP TRUE
J 0
(-3150 3600);
DISPLAY 0.872340 (-3150 3600);
DISPLAY INVISIBLE (-3150 3600);
FORCEPROP 1 LAST PATH I220
J 0
(-3477 3725);
DISPLAY 0.872340 (-3477 3725);
PAINT GREEN (-3477 3725);
DISPLAY INVISIBLE (-3477 3725);
FORCEADD TAP..1
(-3475 3625);
FORCEPROP 3 LASTPIN (-3525 3625) SIG_NAME M_E_CPU1_SB_DQS_DP<8>
J 0
(-3515 3635);
DISPLAY 0.659574 (-3515 3635);
PAINT MONO (-3515 3635);
DISPLAY INVISIBLE (-3515 3635);
FORCEPROP 1 LASTPIN (-3525 3625) BN 8
J 0
(-3537 3633);
DISPLAY 0.489362 (-3537 3633);
PAINT GREEN (-3537 3633);
FORCEPROP 2 LAST CDS_LIB mstr_standard
J 0
(-3475 3625);
DISPLAY 0.723404 (-3475 3625);
PAINT MONO (-3475 3625);
DISPLAY INVISIBLE (-3475 3625);
FORCEPROP 1 LAST BODY_TYPE PLUMBING
J 0
(-3475 3675);
DISPLAY 0.872340 (-3475 3675);
PAINT GREEN (-3475 3675);
DISPLAY INVISIBLE (-3475 3675);
FORCEPROP 1 LAST HDL_TAP TRUE
J 0
(-3150 3500);
DISPLAY 0.872340 (-3150 3500);
DISPLAY INVISIBLE (-3150 3500);
FORCEPROP 1 LAST PATH I221
J 0
(-3477 3625);
DISPLAY 0.872340 (-3477 3625);
PAINT GREEN (-3477 3625);
DISPLAY INVISIBLE (-3477 3625);
FORCEADD TAP..1
(-3475 3525);
FORCEPROP 3 LASTPIN (-3525 3525) SIG_NAME M_E_CPU1_SB_DQS_DP<7>
J 0
(-3515 3535);
DISPLAY 0.659574 (-3515 3535);
PAINT MONO (-3515 3535);
DISPLAY INVISIBLE (-3515 3535);
FORCEPROP 1 LASTPIN (-3525 3525) BN 7
J 0
(-3537 3533);
DISPLAY 0.489362 (-3537 3533);
PAINT GREEN (-3537 3533);
FORCEPROP 2 LAST CDS_LIB mstr_standard
J 0
(-3475 3525);
DISPLAY 0.723404 (-3475 3525);
PAINT MONO (-3475 3525);
DISPLAY INVISIBLE (-3475 3525);
FORCEPROP 1 LAST BODY_TYPE PLUMBING
J 0
(-3475 3575);
DISPLAY 0.872340 (-3475 3575);
PAINT GREEN (-3475 3575);
DISPLAY INVISIBLE (-3475 3575);
FORCEPROP 1 LAST HDL_TAP TRUE
J 0
(-3150 3400);
DISPLAY 0.872340 (-3150 3400);
DISPLAY INVISIBLE (-3150 3400);
FORCEPROP 1 LAST PATH I222
J 0
(-3477 3525);
DISPLAY 0.872340 (-3477 3525);
PAINT GREEN (-3477 3525);
DISPLAY INVISIBLE (-3477 3525);
FORCEADD TAP..1
(-3475 3425);
FORCEPROP 3 LASTPIN (-3525 3425) SIG_NAME M_E_CPU1_SB_DQS_DP<6>
J 0
(-3515 3435);
DISPLAY 0.659574 (-3515 3435);
PAINT MONO (-3515 3435);
DISPLAY INVISIBLE (-3515 3435);
FORCEPROP 1 LASTPIN (-3525 3425) BN 6
J 0
(-3537 3433);
DISPLAY 0.489362 (-3537 3433);
PAINT GREEN (-3537 3433);
FORCEPROP 2 LAST CDS_LIB mstr_standard
J 0
(-3475 3425);
DISPLAY 0.723404 (-3475 3425);
PAINT MONO (-3475 3425);
DISPLAY INVISIBLE (-3475 3425);
FORCEPROP 1 LAST BODY_TYPE PLUMBING
J 0
(-3475 3475);
DISPLAY 0.872340 (-3475 3475);
PAINT GREEN (-3475 3475);
DISPLAY INVISIBLE (-3475 3475);
FORCEPROP 1 LAST HDL_TAP TRUE
J 0
(-3150 3300);
DISPLAY 0.872340 (-3150 3300);
DISPLAY INVISIBLE (-3150 3300);
FORCEPROP 1 LAST PATH I223
J 0
(-3477 3425);
DISPLAY 0.872340 (-3477 3425);
PAINT GREEN (-3477 3425);
DISPLAY INVISIBLE (-3477 3425);
FORCEADD TAP..1
(-3475 3325);
FORCEPROP 3 LASTPIN (-3525 3325) SIG_NAME M_E_CPU1_SB_DQS_DP<5>
J 0
(-3515 3335);
DISPLAY 0.659574 (-3515 3335);
PAINT MONO (-3515 3335);
DISPLAY INVISIBLE (-3515 3335);
FORCEPROP 1 LASTPIN (-3525 3325) BN 5
J 0
(-3537 3333);
DISPLAY 0.489362 (-3537 3333);
PAINT GREEN (-3537 3333);
FORCEPROP 2 LAST CDS_LIB mstr_standard
J 0
(-3475 3325);
DISPLAY 0.723404 (-3475 3325);
PAINT MONO (-3475 3325);
DISPLAY INVISIBLE (-3475 3325);
FORCEPROP 1 LAST BODY_TYPE PLUMBING
J 0
(-3475 3375);
DISPLAY 0.872340 (-3475 3375);
PAINT GREEN (-3475 3375);
DISPLAY INVISIBLE (-3475 3375);
FORCEPROP 1 LAST HDL_TAP TRUE
J 0
(-3150 3200);
DISPLAY 0.872340 (-3150 3200);
DISPLAY INVISIBLE (-3150 3200);
FORCEPROP 1 LAST PATH I224
J 0
(-3477 3325);
DISPLAY 0.872340 (-3477 3325);
PAINT GREEN (-3477 3325);
DISPLAY INVISIBLE (-3477 3325);
FORCEADD TAP..1
(-3275 3075);
FORCEPROP 3 LASTPIN (-3325 3075) SIG_NAME M_E_CPU1_SB_DQS_DN<3>
J 0
(-3315 3085);
DISPLAY 0.659574 (-3315 3085);
PAINT MONO (-3315 3085);
DISPLAY INVISIBLE (-3315 3085);
FORCEPROP 1 LASTPIN (-3325 3075) BN 3
J 0
(-3337 3083);
DISPLAY 0.489362 (-3337 3083);
PAINT GREEN (-3337 3083);
FORCEPROP 2 LAST CDS_LIB mstr_standard
J 0
(-3275 3075);
DISPLAY 0.723404 (-3275 3075);
PAINT MONO (-3275 3075);
DISPLAY INVISIBLE (-3275 3075);
FORCEPROP 1 LAST BODY_TYPE PLUMBING
J 0
(-3275 3125);
DISPLAY 0.872340 (-3275 3125);
PAINT GREEN (-3275 3125);
DISPLAY INVISIBLE (-3275 3125);
FORCEPROP 1 LAST HDL_TAP TRUE
J 0
(-2950 2950);
DISPLAY 0.872340 (-2950 2950);
DISPLAY INVISIBLE (-2950 2950);
FORCEPROP 1 LAST PATH I225
J 0
(-3277 3075);
DISPLAY 0.872340 (-3277 3075);
PAINT GREEN (-3277 3075);
DISPLAY INVISIBLE (-3277 3075);
FORCEADD TAP..1
(-3275 3275);
FORCEPROP 3 LASTPIN (-3325 3275) SIG_NAME M_E_CPU1_SB_DQS_DN<5>
J 0
(-3315 3285);
DISPLAY 0.659574 (-3315 3285);
PAINT MONO (-3315 3285);
DISPLAY INVISIBLE (-3315 3285);
FORCEPROP 1 LASTPIN (-3325 3275) BN 5
J 0
(-3337 3283);
DISPLAY 0.489362 (-3337 3283);
PAINT GREEN (-3337 3283);
FORCEPROP 2 LAST CDS_LIB mstr_standard
J 0
(-3275 3275);
DISPLAY 0.723404 (-3275 3275);
PAINT MONO (-3275 3275);
DISPLAY INVISIBLE (-3275 3275);
FORCEPROP 1 LAST BODY_TYPE PLUMBING
J 0
(-3275 3325);
DISPLAY 0.872340 (-3275 3325);
PAINT GREEN (-3275 3325);
DISPLAY INVISIBLE (-3275 3325);
FORCEPROP 1 LAST HDL_TAP TRUE
J 0
(-2950 3150);
DISPLAY 0.872340 (-2950 3150);
DISPLAY INVISIBLE (-2950 3150);
FORCEPROP 1 LAST PATH I226
J 0
(-3277 3275);
DISPLAY 0.872340 (-3277 3275);
PAINT GREEN (-3277 3275);
DISPLAY INVISIBLE (-3277 3275);
FORCEADD TAP..1
(-3275 3175);
FORCEPROP 3 LASTPIN (-3325 3175) SIG_NAME M_E_CPU1_SB_DQS_DN<4>
J 0
(-3315 3185);
DISPLAY 0.659574 (-3315 3185);
PAINT MONO (-3315 3185);
DISPLAY INVISIBLE (-3315 3185);
FORCEPROP 1 LASTPIN (-3325 3175) BN 4
J 0
(-3337 3183);
DISPLAY 0.489362 (-3337 3183);
PAINT GREEN (-3337 3183);
FORCEPROP 2 LAST CDS_LIB mstr_standard
J 0
(-3275 3175);
DISPLAY 0.723404 (-3275 3175);
PAINT MONO (-3275 3175);
DISPLAY INVISIBLE (-3275 3175);
FORCEPROP 1 LAST BODY_TYPE PLUMBING
J 0
(-3275 3225);
DISPLAY 0.872340 (-3275 3225);
PAINT GREEN (-3275 3225);
DISPLAY INVISIBLE (-3275 3225);
FORCEPROP 1 LAST HDL_TAP TRUE
J 0
(-2950 3050);
DISPLAY 0.872340 (-2950 3050);
DISPLAY INVISIBLE (-2950 3050);
FORCEPROP 1 LAST PATH I227
J 0
(-3277 3175);
DISPLAY 0.872340 (-3277 3175);
PAINT GREEN (-3277 3175);
DISPLAY INVISIBLE (-3277 3175);
FORCEADD TAP..1
(-3275 2875);
FORCEPROP 3 LASTPIN (-3325 2875) SIG_NAME M_E_CPU1_SB_DQS_DN<1>
J 0
(-3315 2885);
DISPLAY 0.659574 (-3315 2885);
PAINT MONO (-3315 2885);
DISPLAY INVISIBLE (-3315 2885);
FORCEPROP 1 LASTPIN (-3325 2875) BN 1
J 0
(-3337 2883);
DISPLAY 0.489362 (-3337 2883);
PAINT GREEN (-3337 2883);
FORCEPROP 2 LAST CDS_LIB mstr_standard
J 0
(-3275 2875);
DISPLAY 0.723404 (-3275 2875);
PAINT MONO (-3275 2875);
DISPLAY INVISIBLE (-3275 2875);
FORCEPROP 1 LAST BODY_TYPE PLUMBING
J 0
(-3275 2925);
DISPLAY 0.872340 (-3275 2925);
PAINT GREEN (-3275 2925);
DISPLAY INVISIBLE (-3275 2925);
FORCEPROP 1 LAST HDL_TAP TRUE
J 0
(-2950 2750);
DISPLAY 0.872340 (-2950 2750);
DISPLAY INVISIBLE (-2950 2750);
FORCEPROP 1 LAST PATH I228
J 0
(-3277 2875);
DISPLAY 0.872340 (-3277 2875);
PAINT GREEN (-3277 2875);
DISPLAY INVISIBLE (-3277 2875);
FORCEADD TAP..1
(-3275 2975);
FORCEPROP 3 LASTPIN (-3325 2975) SIG_NAME M_E_CPU1_SB_DQS_DN<2>
J 0
(-3315 2985);
DISPLAY 0.659574 (-3315 2985);
PAINT MONO (-3315 2985);
DISPLAY INVISIBLE (-3315 2985);
FORCEPROP 1 LASTPIN (-3325 2975) BN 2
J 0
(-3337 2983);
DISPLAY 0.489362 (-3337 2983);
PAINT GREEN (-3337 2983);
FORCEPROP 2 LAST CDS_LIB mstr_standard
J 0
(-3275 2975);
DISPLAY 0.723404 (-3275 2975);
PAINT MONO (-3275 2975);
DISPLAY INVISIBLE (-3275 2975);
FORCEPROP 1 LAST BODY_TYPE PLUMBING
J 0
(-3275 3025);
DISPLAY 0.872340 (-3275 3025);
PAINT GREEN (-3275 3025);
DISPLAY INVISIBLE (-3275 3025);
FORCEPROP 1 LAST HDL_TAP TRUE
J 0
(-2950 2850);
DISPLAY 0.872340 (-2950 2850);
DISPLAY INVISIBLE (-2950 2850);
FORCEPROP 1 LAST PATH I229
J 0
(-3277 2975);
DISPLAY 0.872340 (-3277 2975);
PAINT GREEN (-3277 2975);
DISPLAY INVISIBLE (-3277 2975);
FORCEADD TAP..1
R 2
(-7875 4100);
FORCEPROP 3 LASTPIN (-7825 4100) SIG_NAME M_E_CPU1_SA_CB<4>
J 0
(-7815 4110);
DISPLAY 0.659574 (-7815 4110);
PAINT MONO (-7815 4110);
DISPLAY INVISIBLE (-7815 4110);
FORCEPROP 1 LASTPIN (-7825 4100) BN 4
J 2
(-7813 4108);
DISPLAY 0.489362 (-7813 4108);
PAINT GREEN (-7813 4108);
FORCEPROP 2 LAST CDS_LIB mstr_standard
J 0
(-7875 4100);
DISPLAY 0.723404 (-7875 4100);
PAINT MONO (-7875 4100);
DISPLAY INVISIBLE (-7875 4100);
FORCEPROP 1 LAST BODY_TYPE PLUMBING
J 2
(-7875 4150);
DISPLAY 0.872340 (-7875 4150);
PAINT GREEN (-7875 4150);
DISPLAY INVISIBLE (-7875 4150);
FORCEPROP 1 LAST HDL_TAP TRUE
J 2
(-8200 3975);
DISPLAY 0.872340 (-8200 3975);
DISPLAY INVISIBLE (-8200 3975);
FORCEPROP 1 LAST PATH I23
J 2
(-7873 4100);
DISPLAY 0.872340 (-7873 4100);
PAINT GREEN (-7873 4100);
DISPLAY INVISIBLE (-7873 4100);
FORCEADD TAP..1
(-3475 3225);
FORCEPROP 3 LASTPIN (-3525 3225) SIG_NAME M_E_CPU1_SB_DQS_DP<4>
J 0
(-3515 3235);
DISPLAY 0.659574 (-3515 3235);
PAINT MONO (-3515 3235);
DISPLAY INVISIBLE (-3515 3235);
FORCEPROP 1 LASTPIN (-3525 3225) BN 4
J 0
(-3537 3233);
DISPLAY 0.489362 (-3537 3233);
PAINT GREEN (-3537 3233);
FORCEPROP 2 LAST CDS_LIB mstr_standard
J 0
(-3475 3225);
DISPLAY 0.723404 (-3475 3225);
PAINT MONO (-3475 3225);
DISPLAY INVISIBLE (-3475 3225);
FORCEPROP 1 LAST BODY_TYPE PLUMBING
J 0
(-3475 3275);
DISPLAY 0.872340 (-3475 3275);
PAINT GREEN (-3475 3275);
DISPLAY INVISIBLE (-3475 3275);
FORCEPROP 1 LAST HDL_TAP TRUE
J 0
(-3150 3100);
DISPLAY 0.872340 (-3150 3100);
DISPLAY INVISIBLE (-3150 3100);
FORCEPROP 1 LAST PATH I230
J 0
(-3477 3225);
DISPLAY 0.872340 (-3477 3225);
PAINT GREEN (-3477 3225);
DISPLAY INVISIBLE (-3477 3225);
FORCEADD TAP..1
(-3475 3125);
FORCEPROP 3 LASTPIN (-3525 3125) SIG_NAME M_E_CPU1_SB_DQS_DP<3>
J 0
(-3515 3135);
DISPLAY 0.659574 (-3515 3135);
PAINT MONO (-3515 3135);
DISPLAY INVISIBLE (-3515 3135);
FORCEPROP 1 LASTPIN (-3525 3125) BN 3
J 0
(-3537 3133);
DISPLAY 0.489362 (-3537 3133);
PAINT GREEN (-3537 3133);
FORCEPROP 2 LAST CDS_LIB mstr_standard
J 0
(-3475 3125);
DISPLAY 0.723404 (-3475 3125);
PAINT MONO (-3475 3125);
DISPLAY INVISIBLE (-3475 3125);
FORCEPROP 1 LAST BODY_TYPE PLUMBING
J 0
(-3475 3175);
DISPLAY 0.872340 (-3475 3175);
PAINT GREEN (-3475 3175);
DISPLAY INVISIBLE (-3475 3175);
FORCEPROP 1 LAST HDL_TAP TRUE
J 0
(-3150 3000);
DISPLAY 0.872340 (-3150 3000);
DISPLAY INVISIBLE (-3150 3000);
FORCEPROP 1 LAST PATH I231
J 0
(-3477 3125);
DISPLAY 0.872340 (-3477 3125);
PAINT GREEN (-3477 3125);
DISPLAY INVISIBLE (-3477 3125);
FORCEADD TAP..1
(-3475 3025);
FORCEPROP 3 LASTPIN (-3525 3025) SIG_NAME M_E_CPU1_SB_DQS_DP<2>
J 0
(-3515 3035);
DISPLAY 0.659574 (-3515 3035);
PAINT MONO (-3515 3035);
DISPLAY INVISIBLE (-3515 3035);
FORCEPROP 1 LASTPIN (-3525 3025) BN 2
J 0
(-3537 3033);
DISPLAY 0.489362 (-3537 3033);
PAINT GREEN (-3537 3033);
FORCEPROP 2 LAST CDS_LIB mstr_standard
J 0
(-3475 3025);
DISPLAY 0.723404 (-3475 3025);
PAINT MONO (-3475 3025);
DISPLAY INVISIBLE (-3475 3025);
FORCEPROP 1 LAST BODY_TYPE PLUMBING
J 0
(-3475 3075);
DISPLAY 0.872340 (-3475 3075);
PAINT GREEN (-3475 3075);
DISPLAY INVISIBLE (-3475 3075);
FORCEPROP 1 LAST HDL_TAP TRUE
J 0
(-3150 2900);
DISPLAY 0.872340 (-3150 2900);
DISPLAY INVISIBLE (-3150 2900);
FORCEPROP 1 LAST PATH I232
J 0
(-3477 3025);
DISPLAY 0.872340 (-3477 3025);
PAINT GREEN (-3477 3025);
DISPLAY INVISIBLE (-3477 3025);
FORCEADD TAP..1
(-3475 2925);
FORCEPROP 3 LASTPIN (-3525 2925) SIG_NAME M_E_CPU1_SB_DQS_DP<1>
J 0
(-3515 2935);
DISPLAY 0.659574 (-3515 2935);
PAINT MONO (-3515 2935);
DISPLAY INVISIBLE (-3515 2935);
FORCEPROP 1 LASTPIN (-3525 2925) BN 1
J 0
(-3537 2933);
DISPLAY 0.489362 (-3537 2933);
PAINT GREEN (-3537 2933);
FORCEPROP 2 LAST CDS_LIB mstr_standard
J 0
(-3475 2925);
DISPLAY 0.723404 (-3475 2925);
PAINT MONO (-3475 2925);
DISPLAY INVISIBLE (-3475 2925);
FORCEPROP 1 LAST BODY_TYPE PLUMBING
J 0
(-3475 2975);
DISPLAY 0.872340 (-3475 2975);
PAINT GREEN (-3475 2975);
DISPLAY INVISIBLE (-3475 2975);
FORCEPROP 1 LAST HDL_TAP TRUE
J 0
(-3150 2800);
DISPLAY 0.872340 (-3150 2800);
DISPLAY INVISIBLE (-3150 2800);
FORCEPROP 1 LAST PATH I233
J 0
(-3477 2925);
DISPLAY 0.872340 (-3477 2925);
PAINT GREEN (-3477 2925);
DISPLAY INVISIBLE (-3477 2925);
FORCEADD TAP..1
(-3475 2825);
FORCEPROP 3 LASTPIN (-3525 2825) SIG_NAME M_E_CPU1_SB_DQS_DP<0>
J 0
(-3515 2835);
DISPLAY 0.659574 (-3515 2835);
PAINT MONO (-3515 2835);
DISPLAY INVISIBLE (-3515 2835);
FORCEPROP 1 LASTPIN (-3525 2825) BN 0
J 0
(-3537 2833);
DISPLAY 0.489362 (-3537 2833);
PAINT GREEN (-3537 2833);
FORCEPROP 2 LAST CDS_LIB mstr_standard
J 0
(-3475 2825);
DISPLAY 0.723404 (-3475 2825);
PAINT MONO (-3475 2825);
DISPLAY INVISIBLE (-3475 2825);
FORCEPROP 1 LAST BODY_TYPE PLUMBING
J 0
(-3475 2875);
DISPLAY 0.872340 (-3475 2875);
PAINT GREEN (-3475 2875);
DISPLAY INVISIBLE (-3475 2875);
FORCEPROP 1 LAST HDL_TAP TRUE
J 0
(-3150 2700);
DISPLAY 0.872340 (-3150 2700);
DISPLAY INVISIBLE (-3150 2700);
FORCEPROP 1 LAST PATH I234
J 0
(-3477 2825);
DISPLAY 0.872340 (-3477 2825);
PAINT GREEN (-3477 2825);
DISPLAY INVISIBLE (-3477 2825);
FORCEADD TAP..1
(-3275 2775);
FORCEPROP 3 LASTPIN (-3325 2775) SIG_NAME M_E_CPU1_SB_DQS_DN<0>
J 0
(-3315 2785);
DISPLAY 0.659574 (-3315 2785);
PAINT MONO (-3315 2785);
DISPLAY INVISIBLE (-3315 2785);
FORCEPROP 1 LASTPIN (-3325 2775) BN 0
J 0
(-3337 2783);
DISPLAY 0.489362 (-3337 2783);
PAINT GREEN (-3337 2783);
FORCEPROP 2 LAST CDS_LIB mstr_standard
J 0
(-3275 2775);
DISPLAY 0.723404 (-3275 2775);
PAINT MONO (-3275 2775);
DISPLAY INVISIBLE (-3275 2775);
FORCEPROP 1 LAST BODY_TYPE PLUMBING
J 0
(-3275 2825);
DISPLAY 0.872340 (-3275 2825);
PAINT GREEN (-3275 2825);
DISPLAY INVISIBLE (-3275 2825);
FORCEPROP 1 LAST HDL_TAP TRUE
J 0
(-2950 2650);
DISPLAY 0.872340 (-2950 2650);
DISPLAY INVISIBLE (-2950 2650);
FORCEPROP 1 LAST PATH I235
J 0
(-3277 2775);
DISPLAY 0.872340 (-3277 2775);
PAINT GREEN (-3277 2775);
DISPLAY INVISIBLE (-3277 2775);
FORCEADD SCONN288_DDR506112002KQ..2
(-4425 3775);
FORCEPROP 1 LAST LOCATION J32
J 0
(-5025 5100);
DISPLAY 0.468085 (-5025 5100);
PAINT SKYBLUE (-5025 5100);
FORCEPROP 0 LAST $SEC 2
J 0
(-4875 5250);
DISPLAY 0.680851 (-4875 5250);
PAINT MONO (-4875 5250);
DISPLAY INVISIBLE (-4875 5250);
FORCEPROP 0 LAST CDS_SEC 2
J 0
(-4875 5250);
DISPLAY 1.021277 (-4875 5250);
DISPLAY INVISIBLE (-4875 5250);
FORCEPROP 0 LASTPIN (-3675 3825) $PN 12
J 0
(-3665 3835);
DISPLAY 0.680851 (-3665 3835);
PAINT MONO (-3665 3835);
FORCEPROP 0 LASTPIN (-3675 3875) $PN 11
J 0
(-3665 3885);
DISPLAY 0.680851 (-3665 3885);
PAINT MONO (-3665 3885);
FORCEPROP 0 LASTPIN (-3675 2775) $PN 105
J 0
(-3665 2785);
DISPLAY 0.680851 (-3665 2785);
PAINT MONO (-3665 2785);
FORCEPROP 0 LASTPIN (-3675 2825) $PN 104
J 0
(-3665 2835);
DISPLAY 0.680851 (-3665 2835);
PAINT MONO (-3665 2835);
FORCEPROP 0 LASTPIN (-3675 3925) $PN 23
J 0
(-3665 3935);
DISPLAY 0.680851 (-3665 3935);
PAINT MONO (-3665 3935);
FORCEPROP 0 LASTPIN (-3675 3975) $PN 22
J 0
(-3665 3985);
DISPLAY 0.680851 (-3665 3985);
PAINT MONO (-3665 3985);
FORCEPROP 0 LASTPIN (-3675 2875) $PN 116
J 0
(-3665 2885);
DISPLAY 0.680851 (-3665 2885);
PAINT MONO (-3665 2885);
FORCEPROP 0 LASTPIN (-3675 2925) $PN 115
J 0
(-3665 2935);
DISPLAY 0.680851 (-3665 2935);
PAINT MONO (-3665 2935);
FORCEPROP 0 LASTPIN (-3675 4025) $PN 34
J 0
(-3665 4035);
DISPLAY 0.680851 (-3665 4035);
PAINT MONO (-3665 4035);
FORCEPROP 0 LASTPIN (-3675 4075) $PN 33
J 0
(-3665 4085);
DISPLAY 0.680851 (-3665 4085);
PAINT MONO (-3665 4085);
FORCEPROP 0 LASTPIN (-3675 2975) $PN 127
J 0
(-3665 2985);
DISPLAY 0.680851 (-3665 2985);
PAINT MONO (-3665 2985);
FORCEPROP 0 LASTPIN (-3675 3025) $PN 126
J 0
(-3665 3035);
DISPLAY 0.680851 (-3665 3035);
PAINT MONO (-3665 3035);
FORCEPROP 0 LASTPIN (-3675 4125) $PN 45
J 0
(-3665 4135);
DISPLAY 0.680851 (-3665 4135);
PAINT MONO (-3665 4135);
FORCEPROP 0 LASTPIN (-3675 4175) $PN 44
J 0
(-3665 4185);
DISPLAY 0.680851 (-3665 4185);
PAINT MONO (-3665 4185);
FORCEPROP 0 LASTPIN (-3675 3075) $PN 138
J 0
(-3665 3085);
DISPLAY 0.680851 (-3665 3085);
PAINT MONO (-3665 3085);
FORCEPROP 0 LASTPIN (-3675 3125) $PN 137
J 0
(-3665 3135);
DISPLAY 0.680851 (-3665 3135);
PAINT MONO (-3665 3135);
FORCEPROP 0 LASTPIN (-3675 4225) $PN 56
J 0
(-3665 4235);
DISPLAY 0.680851 (-3665 4235);
PAINT MONO (-3665 4235);
FORCEPROP 0 LASTPIN (-3675 4275) $PN 55
J 0
(-3665 4285);
DISPLAY 0.680851 (-3665 4285);
PAINT MONO (-3665 4285);
FORCEPROP 0 LASTPIN (-3675 3175) $PN 238
J 0
(-3665 3185);
DISPLAY 0.680851 (-3665 3185);
PAINT MONO (-3665 3185);
FORCEPROP 0 LASTPIN (-3675 3225) $PN 239
J 0
(-3665 3235);
DISPLAY 0.680851 (-3665 3235);
PAINT MONO (-3665 3235);
FORCEPROP 0 LASTPIN (-3675 4325) $PN 156
J 0
(-3665 4335);
DISPLAY 0.680851 (-3665 4335);
PAINT MONO (-3665 4335);
FORCEPROP 0 LASTPIN (-3675 4375) $PN 157
J 0
(-3665 4385);
DISPLAY 0.680851 (-3665 4385);
PAINT MONO (-3665 4385);
FORCEPROP 0 LASTPIN (-3675 3275) $PN 249
J 0
(-3665 3285);
DISPLAY 0.680851 (-3665 3285);
PAINT MONO (-3665 3285);
FORCEPROP 0 LASTPIN (-3675 3325) $PN 250
J 0
(-3665 3335);
DISPLAY 0.680851 (-3665 3335);
PAINT MONO (-3665 3335);
FORCEPROP 0 LASTPIN (-3675 4425) $PN 167
J 0
(-3665 4435);
DISPLAY 0.680851 (-3665 4435);
PAINT MONO (-3665 4435);
FORCEPROP 0 LASTPIN (-3675 4475) $PN 168
J 0
(-3665 4485);
DISPLAY 0.680851 (-3665 4485);
PAINT MONO (-3665 4485);
FORCEPROP 0 LASTPIN (-3675 3375) $PN 260
J 0
(-3665 3385);
DISPLAY 0.680851 (-3665 3385);
PAINT MONO (-3665 3385);
FORCEPROP 0 LASTPIN (-3675 3425) $PN 261
J 0
(-3665 3435);
DISPLAY 0.680851 (-3665 3435);
PAINT MONO (-3665 3435);
FORCEPROP 0 LASTPIN (-3675 4525) $PN 178
J 0
(-3665 4535);
DISPLAY 0.680851 (-3665 4535);
PAINT MONO (-3665 4535);
FORCEPROP 0 LASTPIN (-3675 4575) $PN 179
J 0
(-3665 4585);
DISPLAY 0.680851 (-3665 4585);
PAINT MONO (-3665 4585);
FORCEPROP 0 LASTPIN (-3675 3475) $PN 271
J 0
(-3665 3485);
DISPLAY 0.680851 (-3665 3485);
PAINT MONO (-3665 3485);
FORCEPROP 0 LASTPIN (-3675 3525) $PN 272
J 0
(-3665 3535);
DISPLAY 0.680851 (-3665 3535);
PAINT MONO (-3665 3535);
FORCEPROP 0 LASTPIN (-3675 4625) $PN 189
J 0
(-3665 4635);
DISPLAY 0.680851 (-3665 4635);
PAINT MONO (-3665 4635);
FORCEPROP 0 LASTPIN (-3675 4675) $PN 190
J 0
(-3665 4685);
DISPLAY 0.680851 (-3665 4685);
PAINT MONO (-3665 4685);
FORCEPROP 0 LASTPIN (-3675 3575) $PN 282
J 0
(-3665 3585);
DISPLAY 0.680851 (-3665 3585);
PAINT MONO (-3665 3585);
FORCEPROP 0 LASTPIN (-3675 3625) $PN 283
J 0
(-3665 3635);
DISPLAY 0.680851 (-3665 3635);
PAINT MONO (-3665 3635);
FORCEPROP 0 LASTPIN (-3675 4725) $PN 200
J 0
(-3665 4735);
DISPLAY 0.680851 (-3665 4735);
PAINT MONO (-3665 4735);
FORCEPROP 0 LASTPIN (-3675 4775) $PN 201
J 0
(-3665 4785);
DISPLAY 0.680851 (-3665 4785);
PAINT MONO (-3665 4785);
FORCEPROP 0 LASTPIN (-3675 3675) $PN 94
J 0
(-3665 3685);
DISPLAY 0.680851 (-3665 3685);
PAINT MONO (-3665 3685);
FORCEPROP 0 LASTPIN (-3675 3725) $PN 93
J 0
(-3665 3735);
DISPLAY 0.680851 (-3665 3735);
PAINT MONO (-3665 3735);
FORCEPROP 1 LAST MATERIAL IO
J 0
(-5025 4950);
DISPLAY 0.468085 (-5025 4950);
PAINT SKYBLUE (-5025 4950);
FORCEPROP 2 LAST PART_TYPE SMLF
J 0
(-4875 5200);
DISPLAY 1.021277 (-4875 5200);
FORCEPROP 2 LAST VALUE SCONN288_DDR506112002KQ
J 0
(-4875 5150);
DISPLAY 0.489362 (-4875 5150);
PAINT SKYBLUE (-4875 5150);
FORCEPROP 1 LAST CDS_LMAN_SYM_OUTLINE -600,1150,600,-1150
J 0
(-4425 3775);
DISPLAY 0.468085 (-4425 3775);
PAINT GREEN (-4425 3775);
DISPLAY INVISIBLE (-4425 3775);
FORCEPROP 1 LAST NEEDS_NO_SIZE TRUE
J 0
(-4425 3775);
DISPLAY 0.723404 (-4425 3775);
PAINT GREEN (-4425 3775);
DISPLAY INVISIBLE (-4425 3775);
FORCEPROP 2 LAST CDS_LIB pure_quanta
J 0
(-4425 3775);
DISPLAY INVISIBLE (-4425 3775);
FORCEPROP 1 LAST PATH I236
J 0
(-4425 3775);
DISPLAY 0.723404 (-4425 3775);
PAINT GREEN (-4425 3775);
DISPLAY INVISIBLE (-4425 3775);
FORCEPROP 1 LAST PART_NUMBER DFHST8FS479
J 0
(-5025 5025);
DISPLAY 0.468085 (-5025 5025);
PAINT SKYBLUE (-5025 5025);
DISPLAY INVISIBLE (-5025 5025);
FORCEADD GND..1
(-2875 5825);
FORCEPROP 3 LASTPIN (-2875 5875) SIG_NAME GND\g
J 0
(-2865 5885);
DISPLAY 0.659574 (-2865 5885);
PAINT MONO (-2865 5885);
DISPLAY INVISIBLE (-2865 5885);
FORCEPROP 2 LAST CDS_LIB pure_quanta_power
J 0
(-2875 5825);
DISPLAY INVISIBLE (-2875 5825);
FORCEPROP 2 LAST BOM_COST MEM
J 0
(-2850 5950);
DISPLAY 0.659574 (-2850 5950);
DISPLAY INVISIBLE (-2850 5950);
FORCEPROP 1 LAST SIZE 1B
J 0
(-2800 5775);
DISPLAY 0.723404 (-2800 5775);
PAINT GREEN (-2800 5775);
DISPLAY INVISIBLE (-2800 5775);
FORCEPROP 2 LAST ROOM MEM_EFGH_DECOUPLING_CAPS
J 0
(-2850 5900);
DISPLAY 0.659574 (-2850 5900);
PAINT RED (-2850 5900);
DISPLAY INVISIBLE (-2850 5900);
FORCEPROP 1 LAST HDL_POWER GND
J 0
(-2875 5975);
DISPLAY 0.723404 (-2875 5975);
PAINT GREEN (-2875 5975);
DISPLAY INVISIBLE (-2875 5975);
FORCEPROP 1 LAST PATH I237
J 0
(-2800 5825);
DISPLAY 0.872340 (-2800 5825);
PAINT AQUA (-2800 5825);
DISPLAY INVISIBLE (-2800 5825);
FORCEADD Q_CAP..1
R 2
(-2875 6175);
FORCEPROP 1 LAST LOCATION C183
J 2
(-2925 6275);
DISPLAY 0.489362 (-2925 6275);
PAINT SKYBLUE (-2925 6275);
FORCEPROP 0 LAST $SEC 1
J 0
(-2925 6325);
DISPLAY 0.680851 (-2925 6325);
PAINT MONO (-2925 6325);
DISPLAY INVISIBLE (-2925 6325);
FORCEPROP 0 LAST CDS_SEC 1
J 0
(-2925 6325);
DISPLAY 0.680851 (-2925 6325);
DISPLAY INVISIBLE (-2925 6325);
FORCEPROP 1 LASTPIN (-2875 6275) $PN 1
J 2
(-2885 6255);
DISPLAY 0.489362 (-2885 6255);
PAINT MONO (-2885 6255);
FORCEPROP 1 LASTPIN (-2875 6075) $PN 2
J 2
(-2885 6055);
DISPLAY 0.489362 (-2885 6055);
PAINT MONO (-2885 6055);
FORCEPROP 1 LAST PACK_TYPE C0805
J 2
(-2925 5975);
DISPLAY 0.489362 (-2925 5975);
PAINT SKYBLUE (-2925 5975);
FORCEPROP 1 LAST VOLTAGE 25V
J 2
(-2925 6175);
DISPLAY 0.489362 (-2925 6175);
PAINT SKYBLUE (-2925 6175);
FORCEPROP 1 LAST VALUE 10UF
J 2
(-2925 6225);
DISPLAY 0.489362 (-2925 6225);
PAINT SKYBLUE (-2925 6225);
FORCEPROP 1 LAST TOLERANCE 10%
J 2
(-2925 6125);
DISPLAY 0.489362 (-2925 6125);
PAINT SKYBLUE (-2925 6125);
FORCEPROP 1 LAST MATERIAL X6S
J 2
(-2925 6075);
DISPLAY 0.489362 (-2925 6075);
PAINT SKYBLUE (-2925 6075);
FORCEPROP 2 LAST CDS_LIB pure_quanta
J 0
(-2875 6175);
DISPLAY INVISIBLE (-2875 6175);
FORCEPROP 0 LAST BOM_COST MEM
J 2
(-2930 6320);
DISPLAY 0.595745 (-2930 6320);
PAINT MONO (-2930 6320);
DISPLAY INVISIBLE (-2930 6320);
FORCEPROP 2 LAST ROOM 
J 2
(-2930 6320);
DISPLAY 0.595745 (-2930 6320);
PAINT RED (-2930 6320);
DISPLAY INVISIBLE (-2930 6320);
FORCEPROP 1 LAST PATH I238
J 2
(-2925 6325);
DISPLAY 0.978723 (-2925 6325);
PAINT WHITE (-2925 6325);
DISPLAY INVISIBLE (-2925 6325);
FORCEPROP 1 LAST PART_NUMBER CH6104KEA00
J 2
(-2925 6025);
DISPLAY 0.489362 (-2925 6025);
PAINT SKYBLUE (-2925 6025);
DISPLAY INVISIBLE (-2925 6025);
FORCEADD Q_CAP..1
R 2
(-2300 6175);
FORCEPROP 1 LAST LOCATION C509
J 2
(-2350 6275);
DISPLAY 0.489362 (-2350 6275);
PAINT SKYBLUE (-2350 6275);
FORCEPROP 0 LAST $SEC 1
J 0
(-2350 6325);
DISPLAY 0.680851 (-2350 6325);
PAINT MONO (-2350 6325);
DISPLAY INVISIBLE (-2350 6325);
FORCEPROP 0 LAST CDS_SEC 1
J 0
(-2350 6325);
DISPLAY 0.680851 (-2350 6325);
DISPLAY INVISIBLE (-2350 6325);
FORCEPROP 1 LASTPIN (-2300 6275) $PN 1
J 2
(-2310 6255);
DISPLAY 0.489362 (-2310 6255);
PAINT MONO (-2310 6255);
FORCEPROP 1 LASTPIN (-2300 6075) $PN 2
J 2
(-2310 6055);
DISPLAY 0.489362 (-2310 6055);
PAINT MONO (-2310 6055);
FORCEPROP 1 LAST VALUE 10UF
J 2
(-2350 6225);
DISPLAY 0.489362 (-2350 6225);
PAINT SKYBLUE (-2350 6225);
FORCEPROP 1 LAST VOLTAGE 25V
J 2
(-2350 6175);
DISPLAY 0.489362 (-2350 6175);
PAINT SKYBLUE (-2350 6175);
FORCEPROP 1 LAST TOLERANCE 10%
J 2
(-2350 6125);
DISPLAY 0.489362 (-2350 6125);
PAINT SKYBLUE (-2350 6125);
FORCEPROP 1 LAST PACK_TYPE C0805
J 2
(-2350 5975);
DISPLAY 0.489362 (-2350 5975);
PAINT SKYBLUE (-2350 5975);
FORCEPROP 1 LAST MATERIAL X6S
J 2
(-2350 6075);
DISPLAY 0.489362 (-2350 6075);
PAINT SKYBLUE (-2350 6075);
FORCEPROP 2 LAST CDS_LIB pure_quanta
J 0
(-2300 6175);
DISPLAY INVISIBLE (-2300 6175);
FORCEPROP 0 LAST BOM_COST MEM
J 2
(-2355 6320);
DISPLAY 0.595745 (-2355 6320);
PAINT MONO (-2355 6320);
DISPLAY INVISIBLE (-2355 6320);
FORCEPROP 2 LAST ROOM 
J 2
(-2355 6320);
DISPLAY 0.595745 (-2355 6320);
PAINT RED (-2355 6320);
DISPLAY INVISIBLE (-2355 6320);
FORCEPROP 1 LAST PATH I239
J 2
(-2350 6325);
DISPLAY 0.978723 (-2350 6325);
PAINT WHITE (-2350 6325);
DISPLAY INVISIBLE (-2350 6325);
FORCEPROP 1 LAST PART_NUMBER CH6104KEA00
J 2
(-2350 6025);
DISPLAY 0.489362 (-2350 6025);
PAINT SKYBLUE (-2350 6025);
DISPLAY INVISIBLE (-2350 6025);
FORCEADD TAP..1
R 2
(-7875 4150);
FORCEPROP 3 LASTPIN (-7825 4150) SIG_NAME M_E_CPU1_SA_CB<5>
J 0
(-7815 4160);
DISPLAY 0.659574 (-7815 4160);
PAINT MONO (-7815 4160);
DISPLAY INVISIBLE (-7815 4160);
FORCEPROP 1 LASTPIN (-7825 4150) BN 5
J 2
(-7813 4158);
DISPLAY 0.489362 (-7813 4158);
PAINT GREEN (-7813 4158);
FORCEPROP 2 LAST CDS_LIB mstr_standard
J 0
(-7875 4150);
DISPLAY 0.723404 (-7875 4150);
PAINT MONO (-7875 4150);
DISPLAY INVISIBLE (-7875 4150);
FORCEPROP 1 LAST BODY_TYPE PLUMBING
J 2
(-7875 4200);
DISPLAY 0.872340 (-7875 4200);
PAINT GREEN (-7875 4200);
DISPLAY INVISIBLE (-7875 4200);
FORCEPROP 1 LAST HDL_TAP TRUE
J 2
(-8200 4025);
DISPLAY 0.872340 (-8200 4025);
DISPLAY INVISIBLE (-8200 4025);
FORCEPROP 1 LAST PATH I24
J 2
(-7873 4150);
DISPLAY 0.872340 (-7873 4150);
PAINT GREEN (-7873 4150);
DISPLAY INVISIBLE (-7873 4150);
FORCEADD UNIVERSAL_POWER..1
(-2875 6500);
FORCEPROP 3 LASTPIN (-2875 6450) SIG_NAME P12V_MEM_CPU1\g
J 0
(-2865 6460);
DISPLAY 0.659574 (-2865 6460);
PAINT MONO (-2865 6460);
DISPLAY INVISIBLE (-2865 6460);
FORCEPROP 1 LAST HDL_POWER P12V_MEM_CPU1
J 1
(-2875 6550);
DISPLAY 0.489362 (-2875 6550);
PAINT GREEN (-2875 6550);
FORCEPROP 2 LAST CDS_LIB pure_quanta_power
J 0
(-2875 6500);
DISPLAY INVISIBLE (-2875 6500);
FORCEPROP 1 LAST PATH I240
J 0
(-2825 6525);
DISPLAY 0.872340 (-2825 6525);
PAINT AQUA (-2825 6525);
DISPLAY INVISIBLE (-2825 6525);
FORCEADD OFFPAGE..1
(-8575 2875);
FORCEPROP 2 LAST $XR5 103 
J 0
(-9397 2875);
DISPLAY 0.638298 (-9397 2875);
PAINT MONO (-9397 2875);
FORCEPROP 2 LAST $XR4 101 
J 0
(-9277 2875);
DISPLAY 0.638298 (-9277 2875);
PAINT MONO (-9277 2875);
FORCEPROP 2 LAST $XR3 100 
J 0
(-9157 2875);
DISPLAY 0.638298 (-9157 2875);
PAINT MONO (-9157 2875);
FORCEPROP 2 LAST $XR2 99 
J 0
(-9037 2875);
DISPLAY 0.638298 (-9037 2875);
PAINT MONO (-9037 2875);
FORCEPROP 2 LAST $XR1 98 
J 0
(-8947 2875);
DISPLAY 0.638298 (-8947 2875);
PAINT MONO (-8947 2875);
FORCEPROP 2 LAST $XR0 159 
J 0
(-8857 2875);
DISPLAY 0.638298 (-8857 2875);
PAINT MONO (-8857 2875);
FORCEPROP 2 LAST CDS_LIB mstr_standard
J 0
(-8575 2875);
DISPLAY 0.808511 (-8575 2875);
DISPLAY INVISIBLE (-8575 2875);
FORCEPROP 1 LAST OFFPAGE TRUE
J 0
(-8250 2750);
DISPLAY 0.872340 (-8250 2750);
PAINT GREEN (-8250 2750);
DISPLAY INVISIBLE (-8250 2750);
FORCEPROP 1 LAST COMMENT_BODY TRUE
J 0
(-8450 2775);
DISPLAY 0.872340 (-8450 2775);
PAINT GREEN (-8450 2775);
DISPLAY INVISIBLE (-8450 2775);
FORCEPROP 2 LAST PATH I241
J 0
(-8850 2925);
DISPLAY 0.680851 (-8850 2925);
DISPLAY INVISIBLE (-8850 2925);
FORCEADD Q_RES..1
(-7925 2875);
FORCEPROP 1 LAST LOCATION R1584
J 0
(-7975 2900);
DISPLAY 0.510638 (-7975 2900);
PAINT SKYBLUE (-7975 2900);
FORCEPROP 0 LAST $SEC 1
J 0
(-7975 2975);
DISPLAY 0.680851 (-7975 2975);
PAINT MONO (-7975 2975);
DISPLAY INVISIBLE (-7975 2975);
FORCEPROP 0 LAST CDS_SEC 1
J 0
(-7975 2975);
DISPLAY 0.680851 (-7975 2975);
DISPLAY INVISIBLE (-7975 2975);
FORCEPROP 1 LASTPIN (-8025 2875) $PN 1
J 0
(-8013 2887);
DISPLAY 0.787234 (-8013 2887);
PAINT MONO (-8013 2887);
FORCEPROP 1 LASTPIN (-7825 2875) $PN 2
J 0
(-7863 2887);
DISPLAY 0.787234 (-7863 2887);
PAINT MONO (-7863 2887);
FORCEPROP 1 LAST VALUE 49.9
J 2
(-7775 2925);
DISPLAY 0.510638 (-7775 2925);
PAINT SKYBLUE (-7775 2925);
FORCEPROP 2 LAST CDS_LIB pure_quanta
J 0
(-7925 2875);
DISPLAY INVISIBLE (-7925 2875);
FORCEPROP 1 LAST TOLERANCE 1%
J 0
(-7925 2775);
DISPLAY 0.978723 (-7925 2775);
DISPLAY INVISIBLE (-7925 2775);
FORCEPROP 1 LAST WATTAGE 1/16W
J 2
(-7950 2725);
DISPLAY 0.978723 (-7950 2725);
DISPLAY INVISIBLE (-7950 2725);
FORCEPROP 1 LAST PACK_TYPE 0402LF
J 0
(-7675 2725);
DISPLAY 0.978723 (-7675 2725);
DISPLAY INVISIBLE (-7675 2725);
FORCEPROP 1 LAST MATERIAL CHIP
J 0
(-7925 2725);
DISPLAY 0.978723 (-7925 2725);
DISPLAY INVISIBLE (-7925 2725);
FORCEPROP 1 LAST PATH I242
J 0
(-7975 3025);
DISPLAY 0.978723 (-7975 3025);
PAINT WHITE (-7975 3025);
DISPLAY INVISIBLE (-7975 3025);
FORCEPROP 1 LAST PART_NUMBER CS04992FB07
J 0
(-7975 2975);
DISPLAY 0.978723 (-7975 2975);
DISPLAY INVISIBLE (-7975 2975);
FORCEADD Q_RES..1
(-8300 3100);
FORCEPROP 1 LAST LOCATION R1701
J 0
(-8475 3100);
DISPLAY 0.638298 (-8475 3100);
FORCEPROP 0 LAST $SEC 1
J 0
(-8475 3150);
DISPLAY 0.680851 (-8475 3150);
PAINT MONO (-8475 3150);
DISPLAY INVISIBLE (-8475 3150);
FORCEPROP 0 LAST CDS_SEC 1
J 0
(-8475 3150);
DISPLAY 0.680851 (-8475 3150);
DISPLAY INVISIBLE (-8475 3150);
FORCEPROP 1 LASTPIN (-8400 3100) $PN 1
J 0
(-8388 3112);
DISPLAY 0.787234 (-8388 3112);
PAINT MONO (-8388 3112);
FORCEPROP 1 LASTPIN (-8200 3100) $PN 2
J 0
(-8238 3112);
DISPLAY 0.787234 (-8238 3112);
PAINT MONO (-8238 3112);
FORCEPROP 1 LAST VALUE 10
J 2
(-8150 3100);
DISPLAY 0.404255 (-8150 3100);
FORCEPROP 1 LAST MATERIAL CHIP
J 0
(-8400 3075);
DISPLAY 0.404255 (-8400 3075);
FORCEPROP 1 LAST PACK_TYPE 0402LF
J 0
(-8250 3075);
DISPLAY 0.404255 (-8250 3075);
FORCEPROP 2 LAST CDS_LIB pure_quanta
J 0
(-8300 3100);
DISPLAY INVISIBLE (-8300 3100);
FORCEPROP 1 LAST TOLERANCE 1%
J 0
(-8300 3000);
DISPLAY 0.978723 (-8300 3000);
DISPLAY INVISIBLE (-8300 3000);
FORCEPROP 1 LAST WATTAGE 1/16W
J 2
(-8325 2950);
DISPLAY 0.978723 (-8325 2950);
DISPLAY INVISIBLE (-8325 2950);
FORCEPROP 1 LAST PATH I243
J 0
(-8350 3250);
DISPLAY 0.978723 (-8350 3250);
PAINT WHITE (-8350 3250);
DISPLAY INVISIBLE (-8350 3250);
FORCEPROP 1 LAST PART_NUMBER CS01002FB07
J 0
(-8350 3200);
DISPLAY 0.978723 (-8350 3200);
DISPLAY INVISIBLE (-8350 3200);
FORCEADD OFFPAGE..6
(-8950 2975);
FORCEPROP 2 LAST $XR5 159 
J 0
(-9319 3011);
DISPLAY 0.638298 (-9319 3011);
PAINT MONO (-9319 3011);
FORCEPROP 2 LAST $XR4 103 
J 0
(-9439 2939);
DISPLAY 0.638298 (-9439 2939);
PAINT MONO (-9439 2939);
FORCEPROP 2 LAST $XR3 101 
J 0
(-9319 2939);
DISPLAY 0.638298 (-9319 2939);
PAINT MONO (-9319 2939);
FORCEPROP 2 LAST $XR2 100 
J 0
(-9439 2975);
DISPLAY 0.638298 (-9439 2975);
PAINT MONO (-9439 2975);
FORCEPROP 2 LAST $XR1 99 
J 0
(-9319 2975);
DISPLAY 0.638298 (-9319 2975);
PAINT MONO (-9319 2975);
FORCEPROP 2 LAST $XR0 98 
J 0
(-9229 2975);
DISPLAY 0.638298 (-9229 2975);
PAINT MONO (-9229 2975);
FORCEPROP 2 LAST CDS_LIB mstr_standard
J 0
(-8950 2975);
DISPLAY 0.808511 (-8950 2975);
DISPLAY INVISIBLE (-8950 2975);
FORCEPROP 1 LAST OFFPAGE TRUE
J 0
(-8625 2850);
DISPLAY 0.872340 (-8625 2850);
PAINT GREEN (-8625 2850);
DISPLAY INVISIBLE (-8625 2850);
FORCEPROP 1 LAST COMMENT_BODY TRUE
J 0
(-8850 2900);
DISPLAY 0.872340 (-8850 2900);
PAINT GREEN (-8850 2900);
DISPLAY INVISIBLE (-8850 2900);
FORCEPROP 2 LAST PATH I244
J 0
(-9225 3025);
DISPLAY 0.680851 (-9225 3025);
DISPLAY INVISIBLE (-9225 3025);
FORCEADD OFFPAGE..6
(-8475 4300);
FORCEPROP 2 LAST $XR0 41 
J 0
(-8754 4300);
DISPLAY 0.638298 (-8754 4300);
PAINT MONO (-8754 4300);
FORCEPROP 2 LAST CDS_LIB mstr_standard
J 0
(-8475 4300);
DISPLAY 0.723404 (-8475 4300);
PAINT MONO (-8475 4300);
DISPLAY INVISIBLE (-8475 4300);
FORCEPROP 1 LAST OFFPAGE TRUE
J 0
(-8150 4175);
DISPLAY 0.872340 (-8150 4175);
PAINT GREEN (-8150 4175);
DISPLAY INVISIBLE (-8150 4175);
FORCEPROP 1 LAST COMMENT_BODY TRUE
J 0
(-8375 4225);
DISPLAY 0.872340 (-8375 4225);
PAINT GREEN (-8375 4225);
DISPLAY INVISIBLE (-8375 4225);
FORCEPROP 2 LAST PATH I25
J 0
(-8750 4350);
DISPLAY 1.021277 (-8750 4350);
DISPLAY INVISIBLE (-8750 4350);
FORCEADD OFFPAGE..1
(-8475 4400);
FORCEPROP 2 LAST $XR0 41 
J 0
(-8726 4400);
DISPLAY 0.638298 (-8726 4400);
PAINT MONO (-8726 4400);
FORCEPROP 2 LAST CDS_LIB mstr_standard
J 0
(-8475 4400);
DISPLAY 0.723404 (-8475 4400);
PAINT MONO (-8475 4400);
DISPLAY INVISIBLE (-8475 4400);
FORCEPROP 1 LAST OFFPAGE TRUE
J 0
(-8150 4275);
DISPLAY 0.872340 (-8150 4275);
PAINT GREEN (-8150 4275);
DISPLAY INVISIBLE (-8150 4275);
FORCEPROP 1 LAST COMMENT_BODY TRUE
J 0
(-8350 4300);
DISPLAY 0.872340 (-8350 4300);
PAINT GREEN (-8350 4300);
DISPLAY INVISIBLE (-8350 4300);
FORCEPROP 2 LAST PATH I26
J 0
(-8725 4450);
DISPLAY 1.021277 (-8725 4450);
DISPLAY INVISIBLE (-8725 4450);
FORCEADD OFFPAGE..1
(-8475 4350);
FORCEPROP 2 LAST $XR0 41 
J 0
(-8726 4350);
DISPLAY 0.638298 (-8726 4350);
PAINT MONO (-8726 4350);
FORCEPROP 2 LAST CDS_LIB mstr_standard
J 0
(-8475 4350);
DISPLAY 0.808511 (-8475 4350);
DISPLAY INVISIBLE (-8475 4350);
FORCEPROP 1 LAST OFFPAGE TRUE
J 0
(-8150 4225);
DISPLAY 0.872340 (-8150 4225);
PAINT GREEN (-8150 4225);
DISPLAY INVISIBLE (-8150 4225);
FORCEPROP 1 LAST COMMENT_BODY TRUE
J 0
(-8350 4250);
DISPLAY 0.872340 (-8350 4250);
PAINT GREEN (-8350 4250);
DISPLAY INVISIBLE (-8350 4250);
FORCEPROP 2 LAST PATH I27
J 0
(-8725 4400);
DISPLAY 1.021277 (-8725 4400);
DISPLAY INVISIBLE (-8725 4400);
FORCEADD OFFPAGE..1
(-8475 4500);
FORCEPROP 2 LAST $XR0 41 
J 0
(-8726 4500);
DISPLAY 0.638298 (-8726 4500);
PAINT MONO (-8726 4500);
FORCEPROP 2 LAST CDS_LIB mstr_standard
J 0
(-8475 4500);
DISPLAY 0.808511 (-8475 4500);
DISPLAY INVISIBLE (-8475 4500);
FORCEPROP 1 LAST OFFPAGE TRUE
J 0
(-8150 4375);
DISPLAY 0.872340 (-8150 4375);
PAINT GREEN (-8150 4375);
DISPLAY INVISIBLE (-8150 4375);
FORCEPROP 1 LAST COMMENT_BODY TRUE
J 0
(-8350 4400);
DISPLAY 0.872340 (-8350 4400);
PAINT GREEN (-8350 4400);
DISPLAY INVISIBLE (-8350 4400);
FORCEPROP 2 LAST PATH I28
J 0
(-8725 4550);
DISPLAY 1.021277 (-8725 4550);
DISPLAY INVISIBLE (-8725 4550);
FORCEADD OFFPAGE..1
(-8475 4550);
FORCEPROP 2 LAST $XR0 41 
J 0
(-8726 4550);
DISPLAY 0.638298 (-8726 4550);
PAINT MONO (-8726 4550);
FORCEPROP 2 LAST CDS_LIB mstr_standard
J 0
(-8475 4550);
DISPLAY 0.723404 (-8475 4550);
PAINT MONO (-8475 4550);
DISPLAY INVISIBLE (-8475 4550);
FORCEPROP 1 LAST OFFPAGE TRUE
J 0
(-8150 4425);
DISPLAY 0.872340 (-8150 4425);
PAINT GREEN (-8150 4425);
DISPLAY INVISIBLE (-8150 4425);
FORCEPROP 1 LAST COMMENT_BODY TRUE
J 0
(-8350 4450);
DISPLAY 0.872340 (-8350 4450);
PAINT GREEN (-8350 4450);
DISPLAY INVISIBLE (-8350 4450);
FORCEPROP 2 LAST PATH I29
J 0
(-8725 4600);
DISPLAY 1.021277 (-8725 4600);
DISPLAY INVISIBLE (-8725 4600);
FORCEADD OFFPAGE..5
(-8475 2200);
FORCEPROP 2 LAST $XR0 41 
J 0
(-8699 2200);
DISPLAY 0.638298 (-8699 2200);
PAINT MONO (-8699 2200);
FORCEPROP 2 LAST CDS_LIB mstr_standard
J 0
(-8475 2200);
DISPLAY 0.808511 (-8475 2200);
DISPLAY INVISIBLE (-8475 2200);
FORCEPROP 1 LAST OFFPAGE TRUE
J 0
(-8150 2075);
DISPLAY 0.872340 (-8150 2075);
PAINT GREEN (-8150 2075);
DISPLAY INVISIBLE (-8150 2075);
FORCEPROP 1 LAST COMMENT_BODY TRUE
J 0
(-8375 2125);
DISPLAY 0.872340 (-8375 2125);
PAINT GREEN (-8375 2125);
DISPLAY INVISIBLE (-8375 2125);
FORCEPROP 2 LAST PATH I3
J 0
(-8725 2250);
DISPLAY 1.021277 (-8725 2250);
DISPLAY INVISIBLE (-8725 2250);
FORCEADD OFFPAGE..1
(-8475 4650);
FORCEPROP 2 LAST $XR0 41 
J 0
(-8726 4650);
DISPLAY 0.638298 (-8726 4650);
PAINT MONO (-8726 4650);
FORCEPROP 2 LAST CDS_LIB mstr_standard
J 0
(-8475 4650);
DISPLAY 0.808511 (-8475 4650);
DISPLAY INVISIBLE (-8475 4650);
FORCEPROP 1 LAST OFFPAGE TRUE
J 0
(-8150 4525);
DISPLAY 0.872340 (-8150 4525);
PAINT GREEN (-8150 4525);
DISPLAY INVISIBLE (-8150 4525);
FORCEPROP 1 LAST COMMENT_BODY TRUE
J 0
(-8350 4550);
DISPLAY 0.872340 (-8350 4550);
PAINT GREEN (-8350 4550);
DISPLAY INVISIBLE (-8350 4550);
FORCEPROP 2 LAST PATH I30
J 0
(-8725 4700);
DISPLAY 1.021277 (-8725 4700);
DISPLAY INVISIBLE (-8725 4700);
FORCEADD OFFPAGE..1
(-8475 4700);
FORCEPROP 2 LAST $XR0 41 
J 0
(-8726 4700);
DISPLAY 0.638298 (-8726 4700);
PAINT MONO (-8726 4700);
FORCEPROP 2 LAST CDS_LIB mstr_standard
J 0
(-8475 4700);
DISPLAY 0.723404 (-8475 4700);
PAINT MONO (-8475 4700);
DISPLAY INVISIBLE (-8475 4700);
FORCEPROP 1 LAST OFFPAGE TRUE
J 0
(-8150 4575);
DISPLAY 0.872340 (-8150 4575);
PAINT GREEN (-8150 4575);
DISPLAY INVISIBLE (-8150 4575);
FORCEPROP 1 LAST COMMENT_BODY TRUE
J 0
(-8350 4600);
DISPLAY 0.872340 (-8350 4600);
PAINT GREEN (-8350 4600);
DISPLAY INVISIBLE (-8350 4600);
FORCEPROP 2 LAST PATH I31
J 0
(-8725 4750);
DISPLAY 1.021277 (-8725 4750);
DISPLAY INVISIBLE (-8725 4750);
FORCEADD OFFPAGE..1
(-8475 4800);
FORCEPROP 2 LAST $XR0 41 
J 0
(-8726 4800);
DISPLAY 0.638298 (-8726 4800);
PAINT MONO (-8726 4800);
FORCEPROP 2 LAST CDS_LIB mstr_standard
J 0
(-8475 4800);
DISPLAY 0.808511 (-8475 4800);
DISPLAY INVISIBLE (-8475 4800);
FORCEPROP 1 LAST OFFPAGE TRUE
J 0
(-8150 4675);
DISPLAY 0.872340 (-8150 4675);
PAINT GREEN (-8150 4675);
DISPLAY INVISIBLE (-8150 4675);
FORCEPROP 1 LAST COMMENT_BODY TRUE
J 0
(-8350 4700);
DISPLAY 0.872340 (-8350 4700);
PAINT GREEN (-8350 4700);
DISPLAY INVISIBLE (-8350 4700);
FORCEPROP 2 LAST PATH I32
J 0
(-8725 4850);
DISPLAY 1.021277 (-8725 4850);
DISPLAY INVISIBLE (-8725 4850);
FORCEADD OFFPAGE..1
(-8475 4850);
FORCEPROP 2 LAST $XR0 41 
J 0
(-8726 4850);
DISPLAY 0.638298 (-8726 4850);
PAINT MONO (-8726 4850);
FORCEPROP 2 LAST CDS_LIB mstr_standard
J 0
(-8475 4850);
DISPLAY 0.723404 (-8475 4850);
PAINT MONO (-8475 4850);
DISPLAY INVISIBLE (-8475 4850);
FORCEPROP 1 LAST OFFPAGE TRUE
J 0
(-8150 4725);
DISPLAY 0.872340 (-8150 4725);
PAINT GREEN (-8150 4725);
DISPLAY INVISIBLE (-8150 4725);
FORCEPROP 1 LAST COMMENT_BODY TRUE
J 0
(-8350 4750);
DISPLAY 0.872340 (-8350 4750);
PAINT GREEN (-8350 4750);
DISPLAY INVISIBLE (-8350 4750);
FORCEPROP 2 LAST PATH I33
J 0
(-8725 4900);
DISPLAY 1.021277 (-8725 4900);
DISPLAY INVISIBLE (-8725 4900);
FORCEADD TAP..1
R 2
(-7875 4200);
FORCEPROP 3 LASTPIN (-7825 4200) SIG_NAME M_E_CPU1_SA_CB<6>
J 0
(-7815 4210);
DISPLAY 0.659574 (-7815 4210);
PAINT MONO (-7815 4210);
DISPLAY INVISIBLE (-7815 4210);
FORCEPROP 1 LASTPIN (-7825 4200) BN 6
J 2
(-7813 4208);
DISPLAY 0.489362 (-7813 4208);
PAINT GREEN (-7813 4208);
FORCEPROP 2 LAST CDS_LIB mstr_standard
J 0
(-7875 4200);
DISPLAY 0.723404 (-7875 4200);
PAINT MONO (-7875 4200);
DISPLAY INVISIBLE (-7875 4200);
FORCEPROP 1 LAST BODY_TYPE PLUMBING
J 2
(-7875 4250);
DISPLAY 0.872340 (-7875 4250);
PAINT GREEN (-7875 4250);
DISPLAY INVISIBLE (-7875 4250);
FORCEPROP 1 LAST HDL_TAP TRUE
J 2
(-8200 4075);
DISPLAY 0.872340 (-8200 4075);
DISPLAY INVISIBLE (-8200 4075);
FORCEPROP 1 LAST PATH I34
J 2
(-7873 4200);
DISPLAY 0.872340 (-7873 4200);
PAINT GREEN (-7873 4200);
DISPLAY INVISIBLE (-7873 4200);
FORCEADD TAP..1
R 2
(-7875 4250);
FORCEPROP 3 LASTPIN (-7825 4250) SIG_NAME M_E_CPU1_SA_CB<7>
J 0
(-7815 4260);
DISPLAY 0.659574 (-7815 4260);
PAINT MONO (-7815 4260);
DISPLAY INVISIBLE (-7815 4260);
FORCEPROP 1 LASTPIN (-7825 4250) BN 7
J 2
(-7813 4258);
DISPLAY 0.489362 (-7813 4258);
PAINT GREEN (-7813 4258);
FORCEPROP 2 LAST CDS_LIB mstr_standard
J 0
(-7875 4250);
DISPLAY 0.723404 (-7875 4250);
PAINT MONO (-7875 4250);
DISPLAY INVISIBLE (-7875 4250);
FORCEPROP 1 LAST BODY_TYPE PLUMBING
J 2
(-7875 4300);
DISPLAY 0.872340 (-7875 4300);
PAINT GREEN (-7875 4300);
DISPLAY INVISIBLE (-7875 4300);
FORCEPROP 1 LAST HDL_TAP TRUE
J 2
(-8200 4125);
DISPLAY 0.872340 (-8200 4125);
DISPLAY INVISIBLE (-8200 4125);
FORCEPROP 1 LAST PATH I35
J 2
(-7873 4250);
DISPLAY 0.872340 (-7873 4250);
PAINT GREEN (-7873 4250);
DISPLAY INVISIBLE (-7873 4250);
FORCEADD TAP..1
R 2
(-7875 5000);
FORCEPROP 3 LASTPIN (-7825 5000) SIG_NAME M_E_CPU1_SB_CA<1>
J 0
(-7815 5010);
DISPLAY 0.659574 (-7815 5010);
PAINT MONO (-7815 5010);
DISPLAY INVISIBLE (-7815 5010);
FORCEPROP 1 LASTPIN (-7825 5000) BN 1
J 2
(-7813 5008);
DISPLAY 0.489362 (-7813 5008);
PAINT GREEN (-7813 5008);
FORCEPROP 2 LAST CDS_LIB mstr_standard
J 0
(-7875 5000);
DISPLAY 0.723404 (-7875 5000);
PAINT MONO (-7875 5000);
DISPLAY INVISIBLE (-7875 5000);
FORCEPROP 1 LAST BODY_TYPE PLUMBING
J 2
(-7875 5050);
DISPLAY 0.872340 (-7875 5050);
PAINT GREEN (-7875 5050);
DISPLAY INVISIBLE (-7875 5050);
FORCEPROP 1 LAST HDL_TAP TRUE
J 2
(-8200 4875);
DISPLAY 0.872340 (-8200 4875);
DISPLAY INVISIBLE (-8200 4875);
FORCEPROP 1 LAST PATH I36
J 2
(-7873 5000);
DISPLAY 0.872340 (-7873 5000);
PAINT GREEN (-7873 5000);
DISPLAY INVISIBLE (-7873 5000);
FORCEADD TAP..1
R 2
(-7875 4950);
FORCEPROP 3 LASTPIN (-7825 4950) SIG_NAME M_E_CPU1_SB_CA<0>
J 0
(-7815 4960);
DISPLAY 0.659574 (-7815 4960);
PAINT MONO (-7815 4960);
DISPLAY INVISIBLE (-7815 4960);
FORCEPROP 1 LASTPIN (-7825 4950) BN 0
J 2
(-7813 4958);
DISPLAY 0.489362 (-7813 4958);
PAINT GREEN (-7813 4958);
FORCEPROP 2 LAST CDS_LIB mstr_standard
J 0
(-7875 4950);
DISPLAY 0.723404 (-7875 4950);
PAINT MONO (-7875 4950);
DISPLAY INVISIBLE (-7875 4950);
FORCEPROP 1 LAST BODY_TYPE PLUMBING
J 2
(-7875 5000);
DISPLAY 0.872340 (-7875 5000);
PAINT GREEN (-7875 5000);
DISPLAY INVISIBLE (-7875 5000);
FORCEPROP 1 LAST HDL_TAP TRUE
J 2
(-8200 4825);
DISPLAY 0.872340 (-8200 4825);
DISPLAY INVISIBLE (-8200 4825);
FORCEPROP 1 LAST PATH I37
J 2
(-7873 4950);
DISPLAY 0.872340 (-7873 4950);
PAINT GREEN (-7873 4950);
DISPLAY INVISIBLE (-7873 4950);
FORCEADD TAP..1
R 2
(-7875 5050);
FORCEPROP 3 LASTPIN (-7825 5050) SIG_NAME M_E_CPU1_SB_CA<2>
J 0
(-7815 5060);
DISPLAY 0.659574 (-7815 5060);
PAINT MONO (-7815 5060);
DISPLAY INVISIBLE (-7815 5060);
FORCEPROP 1 LASTPIN (-7825 5050) BN 2
J 2
(-7813 5058);
DISPLAY 0.489362 (-7813 5058);
PAINT GREEN (-7813 5058);
FORCEPROP 2 LAST CDS_LIB mstr_standard
J 0
(-7875 5050);
DISPLAY 0.723404 (-7875 5050);
PAINT MONO (-7875 5050);
DISPLAY INVISIBLE (-7875 5050);
FORCEPROP 1 LAST BODY_TYPE PLUMBING
J 2
(-7875 5100);
DISPLAY 0.872340 (-7875 5100);
PAINT GREEN (-7875 5100);
DISPLAY INVISIBLE (-7875 5100);
FORCEPROP 1 LAST HDL_TAP TRUE
J 2
(-8200 4925);
DISPLAY 0.872340 (-8200 4925);
DISPLAY INVISIBLE (-8200 4925);
FORCEPROP 1 LAST PATH I38
J 2
(-7873 5050);
DISPLAY 0.872340 (-7873 5050);
PAINT GREEN (-7873 5050);
DISPLAY INVISIBLE (-7873 5050);
FORCEADD TAP..1
R 2
(-7875 5100);
FORCEPROP 3 LASTPIN (-7825 5100) SIG_NAME M_E_CPU1_SB_CA<3>
J 0
(-7815 5110);
DISPLAY 0.659574 (-7815 5110);
PAINT MONO (-7815 5110);
DISPLAY INVISIBLE (-7815 5110);
FORCEPROP 1 LASTPIN (-7825 5100) BN 3
J 2
(-7813 5108);
DISPLAY 0.489362 (-7813 5108);
PAINT GREEN (-7813 5108);
FORCEPROP 2 LAST CDS_LIB mstr_standard
J 0
(-7875 5100);
DISPLAY 0.723404 (-7875 5100);
PAINT MONO (-7875 5100);
DISPLAY INVISIBLE (-7875 5100);
FORCEPROP 1 LAST BODY_TYPE PLUMBING
J 2
(-7875 5150);
DISPLAY 0.872340 (-7875 5150);
PAINT GREEN (-7875 5150);
DISPLAY INVISIBLE (-7875 5150);
FORCEPROP 1 LAST HDL_TAP TRUE
J 2
(-8200 4975);
DISPLAY 0.872340 (-8200 4975);
DISPLAY INVISIBLE (-8200 4975);
FORCEPROP 1 LAST PATH I39
J 2
(-7873 5100);
DISPLAY 0.872340 (-7873 5100);
PAINT GREEN (-7873 5100);
DISPLAY INVISIBLE (-7873 5100);
FORCEADD TAP..1
R 2
(-7875 5150);
FORCEPROP 3 LASTPIN (-7825 5150) SIG_NAME M_E_CPU1_SB_CA<4>
J 0
(-7815 5160);
DISPLAY 0.659574 (-7815 5160);
PAINT MONO (-7815 5160);
DISPLAY INVISIBLE (-7815 5160);
FORCEPROP 1 LASTPIN (-7825 5150) BN 4
J 2
(-7813 5158);
DISPLAY 0.489362 (-7813 5158);
PAINT GREEN (-7813 5158);
FORCEPROP 2 LAST CDS_LIB mstr_standard
J 0
(-7875 5150);
DISPLAY 0.723404 (-7875 5150);
PAINT MONO (-7875 5150);
DISPLAY INVISIBLE (-7875 5150);
FORCEPROP 1 LAST BODY_TYPE PLUMBING
J 2
(-7875 5200);
DISPLAY 0.872340 (-7875 5200);
PAINT GREEN (-7875 5200);
DISPLAY INVISIBLE (-7875 5200);
FORCEPROP 1 LAST HDL_TAP TRUE
J 2
(-8200 5025);
DISPLAY 0.872340 (-8200 5025);
DISPLAY INVISIBLE (-8200 5025);
FORCEPROP 1 LAST PATH I40
J 2
(-7873 5150);
DISPLAY 0.872340 (-7873 5150);
PAINT GREEN (-7873 5150);
DISPLAY INVISIBLE (-7873 5150);
FORCEADD OFFPAGE..1
(-8475 5300);
FORCEPROP 2 LAST $XR0 41 
J 0
(-8726 5300);
DISPLAY 0.638298 (-8726 5300);
PAINT MONO (-8726 5300);
FORCEPROP 2 LAST CDS_LIB mstr_standard
J 0
(-8475 5300);
DISPLAY 0.723404 (-8475 5300);
PAINT MONO (-8475 5300);
DISPLAY INVISIBLE (-8475 5300);
FORCEPROP 1 LAST OFFPAGE TRUE
J 0
(-8150 5175);
DISPLAY 0.872340 (-8150 5175);
PAINT GREEN (-8150 5175);
DISPLAY INVISIBLE (-8150 5175);
FORCEPROP 1 LAST COMMENT_BODY TRUE
J 0
(-8350 5200);
DISPLAY 0.872340 (-8350 5200);
PAINT GREEN (-8350 5200);
DISPLAY INVISIBLE (-8350 5200);
FORCEPROP 2 LAST PATH I41
J 0
(-8725 5350);
DISPLAY 1.021277 (-8725 5350);
DISPLAY INVISIBLE (-8725 5350);
FORCEADD OFFPAGE..1
(-8475 5700);
FORCEPROP 2 LAST $XR0 41 
J 0
(-8726 5700);
DISPLAY 0.638298 (-8726 5700);
PAINT MONO (-8726 5700);
FORCEPROP 2 LAST CDS_LIB mstr_standard
J 0
(-8475 5700);
DISPLAY 0.723404 (-8475 5700);
PAINT MONO (-8475 5700);
DISPLAY INVISIBLE (-8475 5700);
FORCEPROP 1 LAST OFFPAGE TRUE
J 0
(-8150 5575);
DISPLAY 0.872340 (-8150 5575);
PAINT GREEN (-8150 5575);
DISPLAY INVISIBLE (-8150 5575);
FORCEPROP 1 LAST COMMENT_BODY TRUE
J 0
(-8350 5600);
DISPLAY 0.872340 (-8350 5600);
PAINT GREEN (-8350 5600);
DISPLAY INVISIBLE (-8350 5600);
FORCEPROP 2 LAST PATH I42
J 0
(-8725 5750);
DISPLAY 1.021277 (-8725 5750);
DISPLAY INVISIBLE (-8725 5750);
FORCEADD TAP..1
R 2
(-7875 5250);
FORCEPROP 3 LASTPIN (-7825 5250) SIG_NAME M_E_CPU1_SB_CA<6>
J 0
(-7815 5260);
DISPLAY 0.659574 (-7815 5260);
PAINT MONO (-7815 5260);
DISPLAY INVISIBLE (-7815 5260);
FORCEPROP 1 LASTPIN (-7825 5250) BN 6
J 2
(-7813 5258);
DISPLAY 0.489362 (-7813 5258);
PAINT GREEN (-7813 5258);
FORCEPROP 2 LAST CDS_LIB mstr_standard
J 0
(-7875 5250);
DISPLAY 0.723404 (-7875 5250);
PAINT MONO (-7875 5250);
DISPLAY INVISIBLE (-7875 5250);
FORCEPROP 1 LAST BODY_TYPE PLUMBING
J 2
(-7875 5300);
DISPLAY 0.872340 (-7875 5300);
PAINT GREEN (-7875 5300);
DISPLAY INVISIBLE (-7875 5300);
FORCEPROP 1 LAST HDL_TAP TRUE
J 2
(-8200 5125);
DISPLAY 0.872340 (-8200 5125);
DISPLAY INVISIBLE (-8200 5125);
FORCEPROP 1 LAST PATH I43
J 2
(-7873 5250);
DISPLAY 0.872340 (-7873 5250);
PAINT GREEN (-7873 5250);
DISPLAY INVISIBLE (-7873 5250);
FORCEADD TAP..1
R 2
(-7875 5200);
FORCEPROP 3 LASTPIN (-7825 5200) SIG_NAME M_E_CPU1_SB_CA<5>
J 0
(-7815 5210);
DISPLAY 0.659574 (-7815 5210);
PAINT MONO (-7815 5210);
DISPLAY INVISIBLE (-7815 5210);
FORCEPROP 1 LASTPIN (-7825 5200) BN 5
J 2
(-7813 5208);
DISPLAY 0.489362 (-7813 5208);
PAINT GREEN (-7813 5208);
FORCEPROP 2 LAST CDS_LIB mstr_standard
J 0
(-7875 5200);
DISPLAY 0.723404 (-7875 5200);
PAINT MONO (-7875 5200);
DISPLAY INVISIBLE (-7875 5200);
FORCEPROP 1 LAST BODY_TYPE PLUMBING
J 2
(-7875 5250);
DISPLAY 0.872340 (-7875 5250);
PAINT GREEN (-7875 5250);
DISPLAY INVISIBLE (-7875 5250);
FORCEPROP 1 LAST HDL_TAP TRUE
J 2
(-8200 5075);
DISPLAY 0.872340 (-8200 5075);
DISPLAY INVISIBLE (-8200 5075);
FORCEPROP 1 LAST PATH I44
J 2
(-7873 5200);
DISPLAY 0.872340 (-7873 5200);
PAINT GREEN (-7873 5200);
DISPLAY INVISIBLE (-7873 5200);
FORCEADD TAP..1
R 2
(-7875 5350);
FORCEPROP 3 LASTPIN (-7825 5350) SIG_NAME M_E_CPU1_SA_CA<0>
J 0
(-7815 5360);
DISPLAY 0.659574 (-7815 5360);
PAINT MONO (-7815 5360);
DISPLAY INVISIBLE (-7815 5360);
FORCEPROP 1 LASTPIN (-7825 5350) BN 0
J 2
(-7813 5358);
DISPLAY 0.489362 (-7813 5358);
PAINT GREEN (-7813 5358);
FORCEPROP 2 LAST CDS_LIB mstr_standard
J 0
(-7875 5350);
DISPLAY 0.723404 (-7875 5350);
PAINT MONO (-7875 5350);
DISPLAY INVISIBLE (-7875 5350);
FORCEPROP 1 LAST BODY_TYPE PLUMBING
J 2
(-7875 5400);
DISPLAY 0.872340 (-7875 5400);
PAINT GREEN (-7875 5400);
DISPLAY INVISIBLE (-7875 5400);
FORCEPROP 1 LAST HDL_TAP TRUE
J 2
(-8200 5225);
DISPLAY 0.872340 (-8200 5225);
DISPLAY INVISIBLE (-8200 5225);
FORCEPROP 1 LAST PATH I45
J 2
(-7873 5350);
DISPLAY 0.872340 (-7873 5350);
PAINT GREEN (-7873 5350);
DISPLAY INVISIBLE (-7873 5350);
FORCEADD TAP..1
R 2
(-7875 5400);
FORCEPROP 3 LASTPIN (-7825 5400) SIG_NAME M_E_CPU1_SA_CA<1>
J 0
(-7815 5410);
DISPLAY 0.659574 (-7815 5410);
PAINT MONO (-7815 5410);
DISPLAY INVISIBLE (-7815 5410);
FORCEPROP 1 LASTPIN (-7825 5400) BN 1
J 2
(-7813 5408);
DISPLAY 0.489362 (-7813 5408);
PAINT GREEN (-7813 5408);
FORCEPROP 2 LAST CDS_LIB mstr_standard
J 0
(-7875 5400);
DISPLAY 0.723404 (-7875 5400);
PAINT MONO (-7875 5400);
DISPLAY INVISIBLE (-7875 5400);
FORCEPROP 1 LAST BODY_TYPE PLUMBING
J 2
(-7875 5450);
DISPLAY 0.872340 (-7875 5450);
PAINT GREEN (-7875 5450);
DISPLAY INVISIBLE (-7875 5450);
FORCEPROP 1 LAST HDL_TAP TRUE
J 2
(-8200 5275);
DISPLAY 0.872340 (-8200 5275);
DISPLAY INVISIBLE (-8200 5275);
FORCEPROP 1 LAST PATH I46
J 2
(-7873 5400);
DISPLAY 0.872340 (-7873 5400);
PAINT GREEN (-7873 5400);
DISPLAY INVISIBLE (-7873 5400);
FORCEADD TAP..1
R 2
(-7875 5450);
FORCEPROP 3 LASTPIN (-7825 5450) SIG_NAME M_E_CPU1_SA_CA<2>
J 0
(-7815 5460);
DISPLAY 0.659574 (-7815 5460);
PAINT MONO (-7815 5460);
DISPLAY INVISIBLE (-7815 5460);
FORCEPROP 1 LASTPIN (-7825 5450) BN 2
J 2
(-7813 5458);
DISPLAY 0.489362 (-7813 5458);
PAINT GREEN (-7813 5458);
FORCEPROP 2 LAST CDS_LIB mstr_standard
J 0
(-7875 5450);
DISPLAY 0.723404 (-7875 5450);
PAINT MONO (-7875 5450);
DISPLAY INVISIBLE (-7875 5450);
FORCEPROP 1 LAST BODY_TYPE PLUMBING
J 2
(-7875 5500);
DISPLAY 0.872340 (-7875 5500);
PAINT GREEN (-7875 5500);
DISPLAY INVISIBLE (-7875 5500);
FORCEPROP 1 LAST HDL_TAP TRUE
J 2
(-8200 5325);
DISPLAY 0.872340 (-8200 5325);
DISPLAY INVISIBLE (-8200 5325);
FORCEPROP 1 LAST PATH I47
J 2
(-7873 5450);
DISPLAY 0.872340 (-7873 5450);
PAINT GREEN (-7873 5450);
DISPLAY INVISIBLE (-7873 5450);
FORCEADD TAP..1
R 2
(-7875 5500);
FORCEPROP 3 LASTPIN (-7825 5500) SIG_NAME M_E_CPU1_SA_CA<3>
J 0
(-7815 5510);
DISPLAY 0.659574 (-7815 5510);
PAINT MONO (-7815 5510);
DISPLAY INVISIBLE (-7815 5510);
FORCEPROP 1 LASTPIN (-7825 5500) BN 3
J 2
(-7813 5508);
DISPLAY 0.489362 (-7813 5508);
PAINT GREEN (-7813 5508);
FORCEPROP 2 LAST CDS_LIB mstr_standard
J 0
(-7875 5500);
DISPLAY 0.723404 (-7875 5500);
PAINT MONO (-7875 5500);
DISPLAY INVISIBLE (-7875 5500);
FORCEPROP 1 LAST BODY_TYPE PLUMBING
J 2
(-7875 5550);
DISPLAY 0.872340 (-7875 5550);
PAINT GREEN (-7875 5550);
DISPLAY INVISIBLE (-7875 5550);
FORCEPROP 1 LAST HDL_TAP TRUE
J 2
(-8200 5375);
DISPLAY 0.872340 (-8200 5375);
DISPLAY INVISIBLE (-8200 5375);
FORCEPROP 1 LAST PATH I48
J 2
(-7873 5500);
DISPLAY 0.872340 (-7873 5500);
PAINT GREEN (-7873 5500);
DISPLAY INVISIBLE (-7873 5500);
FORCEADD TAP..1
R 2
(-7875 5550);
FORCEPROP 3 LASTPIN (-7825 5550) SIG_NAME M_E_CPU1_SA_CA<4>
J 0
(-7815 5560);
DISPLAY 0.659574 (-7815 5560);
PAINT MONO (-7815 5560);
DISPLAY INVISIBLE (-7815 5560);
FORCEPROP 1 LASTPIN (-7825 5550) BN 4
J 2
(-7813 5558);
DISPLAY 0.489362 (-7813 5558);
PAINT GREEN (-7813 5558);
FORCEPROP 2 LAST CDS_LIB mstr_standard
J 0
(-7875 5550);
DISPLAY 0.723404 (-7875 5550);
PAINT MONO (-7875 5550);
DISPLAY INVISIBLE (-7875 5550);
FORCEPROP 1 LAST BODY_TYPE PLUMBING
J 2
(-7875 5600);
DISPLAY 0.872340 (-7875 5600);
PAINT GREEN (-7875 5600);
DISPLAY INVISIBLE (-7875 5600);
FORCEPROP 1 LAST HDL_TAP TRUE
J 2
(-8200 5425);
DISPLAY 0.872340 (-8200 5425);
DISPLAY INVISIBLE (-8200 5425);
FORCEPROP 1 LAST PATH I49
J 2
(-7873 5550);
DISPLAY 0.872340 (-7873 5550);
PAINT GREEN (-7873 5550);
DISPLAY INVISIBLE (-7873 5550);
FORCEADD TAP..1
R 2
(-7875 5600);
FORCEPROP 3 LASTPIN (-7825 5600) SIG_NAME M_E_CPU1_SA_CA<5>
J 0
(-7815 5610);
DISPLAY 0.659574 (-7815 5610);
PAINT MONO (-7815 5610);
DISPLAY INVISIBLE (-7815 5610);
FORCEPROP 1 LASTPIN (-7825 5600) BN 5
J 2
(-7813 5608);
DISPLAY 0.489362 (-7813 5608);
PAINT GREEN (-7813 5608);
FORCEPROP 2 LAST CDS_LIB mstr_standard
J 0
(-7875 5600);
DISPLAY 0.723404 (-7875 5600);
PAINT MONO (-7875 5600);
DISPLAY INVISIBLE (-7875 5600);
FORCEPROP 1 LAST BODY_TYPE PLUMBING
J 2
(-7875 5650);
DISPLAY 0.872340 (-7875 5650);
PAINT GREEN (-7875 5650);
DISPLAY INVISIBLE (-7875 5650);
FORCEPROP 1 LAST HDL_TAP TRUE
J 2
(-8200 5475);
DISPLAY 0.872340 (-8200 5475);
DISPLAY INVISIBLE (-8200 5475);
FORCEPROP 1 LAST PATH I50
J 2
(-7873 5600);
DISPLAY 0.872340 (-7873 5600);
PAINT GREEN (-7873 5600);
DISPLAY INVISIBLE (-7873 5600);
FORCEADD TAP..1
R 2
(-7875 5650);
FORCEPROP 3 LASTPIN (-7825 5650) SIG_NAME M_E_CPU1_SA_CA<6>
J 0
(-7815 5660);
DISPLAY 0.659574 (-7815 5660);
PAINT MONO (-7815 5660);
DISPLAY INVISIBLE (-7815 5660);
FORCEPROP 1 LASTPIN (-7825 5650) BN 6
J 2
(-7813 5658);
DISPLAY 0.489362 (-7813 5658);
PAINT GREEN (-7813 5658);
FORCEPROP 2 LAST CDS_LIB mstr_standard
J 0
(-7875 5650);
DISPLAY 0.723404 (-7875 5650);
PAINT MONO (-7875 5650);
DISPLAY INVISIBLE (-7875 5650);
FORCEPROP 1 LAST BODY_TYPE PLUMBING
J 2
(-7875 5700);
DISPLAY 0.872340 (-7875 5700);
PAINT GREEN (-7875 5700);
DISPLAY INVISIBLE (-7875 5700);
FORCEPROP 1 LAST HDL_TAP TRUE
J 2
(-8200 5525);
DISPLAY 0.872340 (-8200 5525);
DISPLAY INVISIBLE (-8200 5525);
FORCEPROP 1 LAST PATH I51
J 2
(-7873 5650);
DISPLAY 0.872340 (-7873 5650);
PAINT GREEN (-7873 5650);
DISPLAY INVISIBLE (-7873 5650);
FORCEADD SCONN288_DDR506112002KQ..1
(-7025 3900);
FORCEPROP 1 LAST LOCATION J32
J 0
(-7475 5975);
DISPLAY 0.468085 (-7475 5975);
PAINT SKYBLUE (-7475 5975);
FORCEPROP 0 LAST $SEC 1
J 0
(-7475 6125);
DISPLAY 0.680851 (-7475 6125);
PAINT MONO (-7475 6125);
DISPLAY INVISIBLE (-7475 6125);
FORCEPROP 2 LAST CDS_SEC 1
J 0
(-7475 6125);
DISPLAY 1.021277 (-7475 6125);
DISPLAY INVISIBLE (-7475 6125);
FORCEPROP 0 LASTPIN (-7625 3300) $PN 62
J 2
(-7635 3310);
DISPLAY 0.680851 (-7635 3310);
PAINT MONO (-7635 3310);
FORCEPROP 0 LASTPIN (-7625 5350) $PN 66
J 2
(-7635 5360);
DISPLAY 0.680851 (-7635 5360);
PAINT MONO (-7635 5360);
FORCEPROP 0 LASTPIN (-7625 4950) $PN 76
J 2
(-7635 4960);
DISPLAY 0.680851 (-7635 4960);
PAINT MONO (-7635 4960);
FORCEPROP 0 LASTPIN (-7625 5400) $PN 211
J 2
(-7635 5410);
DISPLAY 0.680851 (-7635 5410);
PAINT MONO (-7635 5410);
FORCEPROP 0 LASTPIN (-7625 5000) $PN 221
J 2
(-7635 5010);
DISPLAY 0.680851 (-7635 5010);
PAINT MONO (-7635 5010);
FORCEPROP 0 LASTPIN (-7625 5450) $PN 68
J 2
(-7635 5460);
DISPLAY 0.680851 (-7635 5460);
PAINT MONO (-7635 5460);
FORCEPROP 0 LASTPIN (-7625 5050) $PN 78
J 2
(-7635 5060);
DISPLAY 0.680851 (-7635 5060);
PAINT MONO (-7635 5060);
FORCEPROP 0 LASTPIN (-7625 5500) $PN 213
J 2
(-7635 5510);
DISPLAY 0.680851 (-7635 5510);
PAINT MONO (-7635 5510);
FORCEPROP 0 LASTPIN (-7625 5100) $PN 223
J 2
(-7635 5110);
DISPLAY 0.680851 (-7635 5110);
PAINT MONO (-7635 5110);
FORCEPROP 0 LASTPIN (-7625 5550) $PN 70
J 2
(-7635 5560);
DISPLAY 0.680851 (-7635 5560);
PAINT MONO (-7635 5560);
FORCEPROP 0 LASTPIN (-7625 5150) $PN 80
J 2
(-7635 5160);
DISPLAY 0.680851 (-7635 5160);
PAINT MONO (-7635 5160);
FORCEPROP 0 LASTPIN (-7625 5600) $PN 215
J 2
(-7635 5610);
DISPLAY 0.680851 (-7635 5610);
PAINT MONO (-7635 5610);
FORCEPROP 0 LASTPIN (-7625 5200) $PN 225
J 2
(-7635 5210);
DISPLAY 0.680851 (-7635 5210);
PAINT MONO (-7635 5210);
FORCEPROP 0 LASTPIN (-7625 5650) $PN 72
J 2
(-7635 5660);
DISPLAY 0.680851 (-7635 5660);
PAINT MONO (-7635 5660);
FORCEPROP 0 LASTPIN (-7625 5250) $PN 82
J 2
(-7635 5260);
DISPLAY 0.680851 (-7635 5260);
PAINT MONO (-7635 5260);
FORCEPROP 0 LASTPIN (-7625 3900) $PN 51
J 2
(-7635 3910);
DISPLAY 0.680851 (-7635 3910);
PAINT MONO (-7635 3910);
FORCEPROP 0 LASTPIN (-7625 3450) $PN 96
J 2
(-7635 3460);
DISPLAY 0.680851 (-7635 3460);
PAINT MONO (-7635 3460);
FORCEPROP 0 LASTPIN (-7625 3950) $PN 53
J 2
(-7635 3960);
DISPLAY 0.680851 (-7635 3960);
PAINT MONO (-7635 3960);
FORCEPROP 0 LASTPIN (-7625 3500) $PN 98
J 2
(-7635 3510);
DISPLAY 0.680851 (-7635 3510);
PAINT MONO (-7635 3510);
FORCEPROP 0 LASTPIN (-7625 4000) $PN 196
J 2
(-7635 4010);
DISPLAY 0.680851 (-7635 4010);
PAINT MONO (-7635 4010);
FORCEPROP 0 LASTPIN (-7625 3550) $PN 241
J 2
(-7635 3560);
DISPLAY 0.680851 (-7635 3560);
PAINT MONO (-7635 3560);
FORCEPROP 0 LASTPIN (-7625 4050) $PN 198
J 2
(-7635 4060);
DISPLAY 0.680851 (-7635 4060);
PAINT MONO (-7635 4060);
FORCEPROP 0 LASTPIN (-7625 3600) $PN 243
J 2
(-7635 3610);
DISPLAY 0.680851 (-7635 3610);
PAINT MONO (-7635 3610);
FORCEPROP 0 LASTPIN (-7625 4100) $PN 58
J 2
(-7635 4110);
DISPLAY 0.680851 (-7635 4110);
PAINT MONO (-7635 4110);
FORCEPROP 0 LASTPIN (-7625 3650) $PN 89
J 2
(-7635 3660);
DISPLAY 0.680851 (-7635 3660);
PAINT MONO (-7635 3660);
FORCEPROP 0 LASTPIN (-7625 4150) $PN 60
J 2
(-7635 4160);
DISPLAY 0.680851 (-7635 4160);
PAINT MONO (-7635 4160);
FORCEPROP 0 LASTPIN (-7625 3700) $PN 91
J 2
(-7635 3710);
DISPLAY 0.680851 (-7635 3710);
PAINT MONO (-7635 3710);
FORCEPROP 0 LASTPIN (-7625 4200) $PN 203
J 2
(-7635 4210);
DISPLAY 0.680851 (-7635 4210);
PAINT MONO (-7635 4210);
FORCEPROP 0 LASTPIN (-7625 3750) $PN 234
J 2
(-7635 3760);
DISPLAY 0.680851 (-7635 3760);
PAINT MONO (-7635 3760);
FORCEPROP 0 LASTPIN (-7625 4250) $PN 205
J 2
(-7635 4260);
DISPLAY 0.680851 (-7635 4260);
PAINT MONO (-7635 4260);
FORCEPROP 0 LASTPIN (-7625 3800) $PN 236
J 2
(-7635 3810);
DISPLAY 0.680851 (-7635 3810);
PAINT MONO (-7635 3810);
FORCEPROP 0 LASTPIN (-7625 4350) $PN 218
J 2
(-7635 4360);
DISPLAY 0.680851 (-7635 4360);
PAINT MONO (-7635 4360);
FORCEPROP 0 LASTPIN (-7625 4400) $PN 217
J 2
(-7635 4410);
DISPLAY 0.680851 (-7635 4410);
PAINT MONO (-7635 4410);
FORCEPROP 0 LASTPIN (-7625 4650) $PN 64
J 2
(-7635 4660);
DISPLAY 0.680851 (-7635 4660);
PAINT MONO (-7635 4660);
FORCEPROP 0 LASTPIN (-7625 4500) $PN 84
J 2
(-7635 4510);
DISPLAY 0.680851 (-7635 4510);
PAINT MONO (-7635 4510);
FORCEPROP 0 LASTPIN (-7625 4700) $PN 209
J 2
(-7635 4710);
DISPLAY 0.680851 (-7635 4710);
PAINT MONO (-7635 4710);
FORCEPROP 0 LASTPIN (-7625 4550) $PN 229
J 2
(-7635 4560);
DISPLAY 0.680851 (-7635 4560);
PAINT MONO (-7635 4560);
FORCEPROP 0 LASTPIN (-6425 4100) $PN 7
J 0
(-6415 4110);
DISPLAY 0.680851 (-6415 4110);
PAINT MONO (-6415 4110);
FORCEPROP 0 LASTPIN (-6425 2450) $PN 100
J 0
(-6415 2460);
DISPLAY 0.680851 (-6415 2460);
PAINT MONO (-6415 2460);
FORCEPROP 0 LASTPIN (-6425 4150) $PN 9
J 0
(-6415 4160);
DISPLAY 0.680851 (-6415 4160);
PAINT MONO (-6415 4160);
FORCEPROP 0 LASTPIN (-6425 2500) $PN 102
J 0
(-6415 2510);
DISPLAY 0.680851 (-6415 2510);
PAINT MONO (-6415 2510);
FORCEPROP 0 LASTPIN (-6425 4200) $PN 152
J 0
(-6415 4210);
DISPLAY 0.680851 (-6415 4210);
PAINT MONO (-6415 4210);
FORCEPROP 0 LASTPIN (-6425 2550) $PN 245
J 0
(-6415 2560);
DISPLAY 0.680851 (-6415 2560);
PAINT MONO (-6415 2560);
FORCEPROP 0 LASTPIN (-6425 4250) $PN 154
J 0
(-6415 4260);
DISPLAY 0.680851 (-6415 4260);
PAINT MONO (-6415 4260);
FORCEPROP 0 LASTPIN (-6425 2600) $PN 247
J 0
(-6415 2610);
DISPLAY 0.680851 (-6415 2610);
PAINT MONO (-6415 2610);
FORCEPROP 0 LASTPIN (-6425 4300) $PN 14
J 0
(-6415 4310);
DISPLAY 0.680851 (-6415 4310);
PAINT MONO (-6415 4310);
FORCEPROP 0 LASTPIN (-6425 2650) $PN 107
J 0
(-6415 2660);
DISPLAY 0.680851 (-6415 2660);
PAINT MONO (-6415 2660);
FORCEPROP 0 LASTPIN (-6425 4350) $PN 16
J 0
(-6415 4360);
DISPLAY 0.680851 (-6415 4360);
PAINT MONO (-6415 4360);
FORCEPROP 0 LASTPIN (-6425 2700) $PN 109
J 0
(-6415 2710);
DISPLAY 0.680851 (-6415 2710);
PAINT MONO (-6415 2710);
FORCEPROP 0 LASTPIN (-6425 4400) $PN 159
J 0
(-6415 4410);
DISPLAY 0.680851 (-6415 4410);
PAINT MONO (-6415 4410);
FORCEPROP 0 LASTPIN (-6425 2750) $PN 252
J 0
(-6415 2760);
DISPLAY 0.680851 (-6415 2760);
PAINT MONO (-6415 2760);
FORCEPROP 0 LASTPIN (-6425 4450) $PN 161
J 0
(-6415 4460);
DISPLAY 0.680851 (-6415 4460);
PAINT MONO (-6415 4460);
FORCEPROP 0 LASTPIN (-6425 2800) $PN 254
J 0
(-6415 2810);
DISPLAY 0.680851 (-6415 2810);
PAINT MONO (-6415 2810);
FORCEPROP 0 LASTPIN (-6425 4500) $PN 18
J 0
(-6415 4510);
DISPLAY 0.680851 (-6415 4510);
PAINT MONO (-6415 4510);
FORCEPROP 0 LASTPIN (-6425 2850) $PN 111
J 0
(-6415 2860);
DISPLAY 0.680851 (-6415 2860);
PAINT MONO (-6415 2860);
FORCEPROP 0 LASTPIN (-6425 4550) $PN 20
J 0
(-6415 4560);
DISPLAY 0.680851 (-6415 4560);
PAINT MONO (-6415 4560);
FORCEPROP 0 LASTPIN (-6425 2900) $PN 113
J 0
(-6415 2910);
DISPLAY 0.680851 (-6415 2910);
PAINT MONO (-6415 2910);
FORCEPROP 0 LASTPIN (-6425 4600) $PN 163
J 0
(-6415 4610);
DISPLAY 0.680851 (-6415 4610);
PAINT MONO (-6415 4610);
FORCEPROP 0 LASTPIN (-6425 2950) $PN 256
J 0
(-6415 2960);
DISPLAY 0.680851 (-6415 2960);
PAINT MONO (-6415 2960);
FORCEPROP 0 LASTPIN (-6425 4650) $PN 165
J 0
(-6415 4660);
DISPLAY 0.680851 (-6415 4660);
PAINT MONO (-6415 4660);
FORCEPROP 0 LASTPIN (-6425 3000) $PN 258
J 0
(-6415 3010);
DISPLAY 0.680851 (-6415 3010);
PAINT MONO (-6415 3010);
FORCEPROP 0 LASTPIN (-6425 4700) $PN 25
J 0
(-6415 4710);
DISPLAY 0.680851 (-6415 4710);
PAINT MONO (-6415 4710);
FORCEPROP 0 LASTPIN (-6425 3050) $PN 118
J 0
(-6415 3060);
DISPLAY 0.680851 (-6415 3060);
PAINT MONO (-6415 3060);
FORCEPROP 0 LASTPIN (-6425 4750) $PN 27
J 0
(-6415 4760);
DISPLAY 0.680851 (-6415 4760);
PAINT MONO (-6415 4760);
FORCEPROP 0 LASTPIN (-6425 3100) $PN 120
J 0
(-6415 3110);
DISPLAY 0.680851 (-6415 3110);
PAINT MONO (-6415 3110);
FORCEPROP 0 LASTPIN (-6425 4800) $PN 170
J 0
(-6415 4810);
DISPLAY 0.680851 (-6415 4810);
PAINT MONO (-6415 4810);
FORCEPROP 0 LASTPIN (-6425 3150) $PN 263
J 0
(-6415 3160);
DISPLAY 0.680851 (-6415 3160);
PAINT MONO (-6415 3160);
FORCEPROP 0 LASTPIN (-6425 4850) $PN 172
J 0
(-6415 4860);
DISPLAY 0.680851 (-6415 4860);
PAINT MONO (-6415 4860);
FORCEPROP 0 LASTPIN (-6425 3200) $PN 265
J 0
(-6415 3210);
DISPLAY 0.680851 (-6415 3210);
PAINT MONO (-6415 3210);
FORCEPROP 0 LASTPIN (-6425 4900) $PN 29
J 0
(-6415 4910);
DISPLAY 0.680851 (-6415 4910);
PAINT MONO (-6415 4910);
FORCEPROP 0 LASTPIN (-6425 3250) $PN 122
J 0
(-6415 3260);
DISPLAY 0.680851 (-6415 3260);
PAINT MONO (-6415 3260);
FORCEPROP 0 LASTPIN (-6425 4950) $PN 31
J 0
(-6415 4960);
DISPLAY 0.680851 (-6415 4960);
PAINT MONO (-6415 4960);
FORCEPROP 0 LASTPIN (-6425 3300) $PN 124
J 0
(-6415 3310);
DISPLAY 0.680851 (-6415 3310);
PAINT MONO (-6415 3310);
FORCEPROP 0 LASTPIN (-6425 5000) $PN 174
J 0
(-6415 5010);
DISPLAY 0.680851 (-6415 5010);
PAINT MONO (-6415 5010);
FORCEPROP 0 LASTPIN (-6425 3350) $PN 267
J 0
(-6415 3360);
DISPLAY 0.680851 (-6415 3360);
PAINT MONO (-6415 3360);
FORCEPROP 0 LASTPIN (-6425 5050) $PN 176
J 0
(-6415 5060);
DISPLAY 0.680851 (-6415 5060);
PAINT MONO (-6415 5060);
FORCEPROP 0 LASTPIN (-6425 3400) $PN 269
J 0
(-6415 3410);
DISPLAY 0.680851 (-6415 3410);
PAINT MONO (-6415 3410);
FORCEPROP 0 LASTPIN (-6425 5100) $PN 36
J 0
(-6415 5110);
DISPLAY 0.680851 (-6415 5110);
PAINT MONO (-6415 5110);
FORCEPROP 0 LASTPIN (-6425 3450) $PN 129
J 0
(-6415 3460);
DISPLAY 0.680851 (-6415 3460);
PAINT MONO (-6415 3460);
FORCEPROP 0 LASTPIN (-6425 5150) $PN 38
J 0
(-6415 5160);
DISPLAY 0.680851 (-6415 5160);
PAINT MONO (-6415 5160);
FORCEPROP 0 LASTPIN (-6425 3500) $PN 131
J 0
(-6415 3510);
DISPLAY 0.680851 (-6415 3510);
PAINT MONO (-6415 3510);
FORCEPROP 0 LASTPIN (-6425 5200) $PN 181
J 0
(-6415 5210);
DISPLAY 0.680851 (-6415 5210);
PAINT MONO (-6415 5210);
FORCEPROP 0 LASTPIN (-6425 3550) $PN 274
J 0
(-6415 3560);
DISPLAY 0.680851 (-6415 3560);
PAINT MONO (-6415 3560);
FORCEPROP 0 LASTPIN (-6425 5250) $PN 183
J 0
(-6415 5260);
DISPLAY 0.680851 (-6415 5260);
PAINT MONO (-6415 5260);
FORCEPROP 0 LASTPIN (-6425 3600) $PN 276
J 0
(-6415 3610);
DISPLAY 0.680851 (-6415 3610);
PAINT MONO (-6415 3610);
FORCEPROP 0 LASTPIN (-6425 5300) $PN 40
J 0
(-6415 5310);
DISPLAY 0.680851 (-6415 5310);
PAINT MONO (-6415 5310);
FORCEPROP 0 LASTPIN (-6425 3650) $PN 133
J 0
(-6415 3660);
DISPLAY 0.680851 (-6415 3660);
PAINT MONO (-6415 3660);
FORCEPROP 0 LASTPIN (-6425 5350) $PN 42
J 0
(-6415 5360);
DISPLAY 0.680851 (-6415 5360);
PAINT MONO (-6415 5360);
FORCEPROP 0 LASTPIN (-6425 3700) $PN 135
J 0
(-6415 3710);
DISPLAY 0.680851 (-6415 3710);
PAINT MONO (-6415 3710);
FORCEPROP 0 LASTPIN (-6425 5400) $PN 185
J 0
(-6415 5410);
DISPLAY 0.680851 (-6415 5410);
PAINT MONO (-6415 5410);
FORCEPROP 0 LASTPIN (-6425 3750) $PN 278
J 0
(-6415 3760);
DISPLAY 0.680851 (-6415 3760);
PAINT MONO (-6415 3760);
FORCEPROP 0 LASTPIN (-6425 5450) $PN 187
J 0
(-6415 5460);
DISPLAY 0.680851 (-6415 5460);
PAINT MONO (-6415 5460);
FORCEPROP 0 LASTPIN (-6425 3800) $PN 280
J 0
(-6415 3810);
DISPLAY 0.680851 (-6415 3810);
PAINT MONO (-6415 3810);
FORCEPROP 0 LASTPIN (-6425 5500) $PN 47
J 0
(-6415 5510);
DISPLAY 0.680851 (-6415 5510);
PAINT MONO (-6415 5510);
FORCEPROP 0 LASTPIN (-6425 3850) $PN 140
J 0
(-6415 3860);
DISPLAY 0.680851 (-6415 3860);
PAINT MONO (-6415 3860);
FORCEPROP 0 LASTPIN (-6425 5550) $PN 49
J 0
(-6415 5560);
DISPLAY 0.680851 (-6415 5560);
PAINT MONO (-6415 5560);
FORCEPROP 0 LASTPIN (-6425 3900) $PN 142
J 0
(-6415 3910);
DISPLAY 0.680851 (-6415 3910);
PAINT MONO (-6415 3910);
FORCEPROP 0 LASTPIN (-6425 5600) $PN 192
J 0
(-6415 5610);
DISPLAY 0.680851 (-6415 5610);
PAINT MONO (-6415 5610);
FORCEPROP 0 LASTPIN (-6425 3950) $PN 285
J 0
(-6415 3960);
DISPLAY 0.680851 (-6415 3960);
PAINT MONO (-6415 3960);
FORCEPROP 0 LASTPIN (-6425 5650) $PN 194
J 0
(-6415 5660);
DISPLAY 0.680851 (-6415 5660);
PAINT MONO (-6415 5660);
FORCEPROP 0 LASTPIN (-6425 4000) $PN 287
J 0
(-6415 4010);
DISPLAY 0.680851 (-6415 4010);
PAINT MONO (-6415 4010);
FORCEPROP 0 LASTPIN (-7625 3150) $PN 148
J 2
(-7635 3160);
DISPLAY 0.680851 (-7635 3160);
PAINT MONO (-7635 3160);
FORCEPROP 0 LASTPIN (-7625 3050) $PN 4
J 2
(-7635 3060);
DISPLAY 0.680851 (-7635 3060);
PAINT MONO (-7635 3060);
FORCEPROP 0 LASTPIN (-7625 3100) $PN 5
J 2
(-7635 3110);
DISPLAY 0.680851 (-7635 3110);
PAINT MONO (-7635 3110);
FORCEPROP 0 LASTPIN (-7625 2250) $PN 86
J 2
(-7635 2260);
DISPLAY 0.680851 (-7635 2260);
PAINT MONO (-7635 2260);
FORCEPROP 0 LASTPIN (-7625 2200) $PN 87
J 2
(-7635 2210);
DISPLAY 0.680851 (-7635 2210);
PAINT MONO (-7635 2210);
FORCEPROP 0 LASTPIN (-7625 4850) $PN 74
J 2
(-7635 4860);
DISPLAY 0.680851 (-7635 4860);
PAINT MONO (-7635 4860);
FORCEPROP 0 LASTPIN (-7625 4800) $PN 227
J 2
(-7635 4810);
DISPLAY 0.680851 (-7635 4810);
PAINT MONO (-7635 4810);
FORCEPROP 0 LASTPIN (-7625 2800) $PN 147
J 2
(-7635 2810);
DISPLAY 0.680851 (-7635 2810);
PAINT MONO (-7635 2810);
FORCEPROP 0 LASTPIN (-7625 3350) $PN 207
J 2
(-7635 3360);
DISPLAY 0.680851 (-7635 3360);
PAINT MONO (-7635 3360);
FORCEPROP 0 LASTPIN (-7625 2400) $PN 2
J 2
(-7635 2410);
DISPLAY 0.680851 (-7635 2410);
PAINT MONO (-7635 2410);
FORCEPROP 0 LASTPIN (-7625 2450) $PN 144
J 2
(-7635 2460);
DISPLAY 0.680851 (-7635 2460);
PAINT MONO (-7635 2460);
FORCEPROP 0 LASTPIN (-7625 2500) $PN 149
J 2
(-7635 2510);
DISPLAY 0.680851 (-7635 2510);
PAINT MONO (-7635 2510);
FORCEPROP 0 LASTPIN (-7625 2550) $PN 150
J 2
(-7635 2560);
DISPLAY 0.680851 (-7635 2560);
PAINT MONO (-7635 2560);
FORCEPROP 0 LASTPIN (-7625 2600) $PN 220
J 2
(-7635 2610);
DISPLAY 0.680851 (-7635 2610);
PAINT MONO (-7635 2610);
FORCEPROP 0 LASTPIN (-7625 2650) $PN 231
J 2
(-7635 2660);
DISPLAY 0.680851 (-7635 2660);
PAINT MONO (-7635 2660);
FORCEPROP 0 LASTPIN (-7625 2700) $PN 232
J 2
(-7635 2710);
DISPLAY 0.680851 (-7635 2710);
PAINT MONO (-7635 2710);
FORCEPROP 0 LASTPIN (-7625 3200) $PN 3
J 2
(-7635 3210);
DISPLAY 0.680851 (-7635 3210);
PAINT MONO (-7635 3210);
FORCEPROP 2 LAST PART_TYPE SMLF
J 0
(-7475 6075);
DISPLAY 1.021277 (-7475 6075);
FORCEPROP 2 LAST VALUE SCONN288_DDR506112002KQ
J 0
(-7475 6025);
DISPLAY 0.489362 (-7475 6025);
PAINT SKYBLUE (-7475 6025);
FORCEPROP 1 LAST MATERIAL IO
J 0
(-7475 5825);
DISPLAY 0.468085 (-7475 5825);
PAINT SKYBLUE (-7475 5825);
FORCEPROP 1 LAST CDS_LMAN_SYM_OUTLINE -450,1900,450,-1850
J 0
(-7025 3900);
DISPLAY 0.468085 (-7025 3900);
PAINT GREEN (-7025 3900);
DISPLAY INVISIBLE (-7025 3900);
FORCEPROP 1 LAST NEEDS_NO_SIZE TRUE
J 0
(-7025 3900);
DISPLAY 0.723404 (-7025 3900);
PAINT GREEN (-7025 3900);
DISPLAY INVISIBLE (-7025 3900);
FORCEPROP 2 LAST CDS_LIB pure_quanta
J 0
(-7025 3900);
DISPLAY INVISIBLE (-7025 3900);
FORCEPROP 1 LAST PATH I52
J 0
(-7025 3900);
DISPLAY 0.723404 (-7025 3900);
PAINT GREEN (-7025 3900);
DISPLAY INVISIBLE (-7025 3900);
FORCEPROP 1 LAST PART_NUMBER DFHST8FS479
J 0
(-7475 5900);
DISPLAY 0.468085 (-7475 5900);
PAINT SKYBLUE (-7475 5900);
DISPLAY INVISIBLE (-7475 5900);
FORCEADD TAP..1
(-6175 2550);
FORCEPROP 3 LASTPIN (-6225 2550) SIG_NAME M_E_CPU1_SB_DQ<2>
J 0
(-6215 2560);
DISPLAY 0.659574 (-6215 2560);
PAINT MONO (-6215 2560);
DISPLAY INVISIBLE (-6215 2560);
FORCEPROP 1 LASTPIN (-6225 2550) BN 2
J 0
(-6237 2558);
DISPLAY 0.489362 (-6237 2558);
PAINT GREEN (-6237 2558);
FORCEPROP 2 LAST CDS_LIB mstr_standard
J 0
(-6175 2550);
DISPLAY 0.723404 (-6175 2550);
PAINT MONO (-6175 2550);
DISPLAY INVISIBLE (-6175 2550);
FORCEPROP 1 LAST BODY_TYPE PLUMBING
J 0
(-6175 2600);
DISPLAY 0.872340 (-6175 2600);
PAINT GREEN (-6175 2600);
DISPLAY INVISIBLE (-6175 2600);
FORCEPROP 1 LAST HDL_TAP TRUE
J 0
(-5850 2425);
DISPLAY 0.872340 (-5850 2425);
DISPLAY INVISIBLE (-5850 2425);
FORCEPROP 1 LAST PATH I53
J 0
(-6177 2550);
DISPLAY 0.872340 (-6177 2550);
PAINT GREEN (-6177 2550);
DISPLAY INVISIBLE (-6177 2550);
FORCEADD TAP..1
(-6175 2600);
FORCEPROP 3 LASTPIN (-6225 2600) SIG_NAME M_E_CPU1_SB_DQ<3>
J 0
(-6215 2610);
DISPLAY 0.659574 (-6215 2610);
PAINT MONO (-6215 2610);
DISPLAY INVISIBLE (-6215 2610);
FORCEPROP 1 LASTPIN (-6225 2600) BN 3
J 0
(-6237 2608);
DISPLAY 0.489362 (-6237 2608);
PAINT GREEN (-6237 2608);
FORCEPROP 2 LAST CDS_LIB mstr_standard
J 0
(-6175 2600);
DISPLAY 0.723404 (-6175 2600);
PAINT MONO (-6175 2600);
DISPLAY INVISIBLE (-6175 2600);
FORCEPROP 1 LAST BODY_TYPE PLUMBING
J 0
(-6175 2650);
DISPLAY 0.872340 (-6175 2650);
PAINT GREEN (-6175 2650);
DISPLAY INVISIBLE (-6175 2650);
FORCEPROP 1 LAST HDL_TAP TRUE
J 0
(-5850 2475);
DISPLAY 0.872340 (-5850 2475);
DISPLAY INVISIBLE (-5850 2475);
FORCEPROP 1 LAST PATH I54
J 0
(-6177 2600);
DISPLAY 0.872340 (-6177 2600);
PAINT GREEN (-6177 2600);
DISPLAY INVISIBLE (-6177 2600);
FORCEADD TAP..1
(-6175 2450);
FORCEPROP 3 LASTPIN (-6225 2450) SIG_NAME M_E_CPU1_SB_DQ<0>
J 0
(-6215 2460);
DISPLAY 0.659574 (-6215 2460);
PAINT MONO (-6215 2460);
DISPLAY INVISIBLE (-6215 2460);
FORCEPROP 1 LASTPIN (-6225 2450) BN 0
J 0
(-6237 2458);
DISPLAY 0.489362 (-6237 2458);
PAINT GREEN (-6237 2458);
FORCEPROP 2 LAST CDS_LIB mstr_standard
J 0
(-6175 2450);
DISPLAY 0.723404 (-6175 2450);
PAINT MONO (-6175 2450);
DISPLAY INVISIBLE (-6175 2450);
FORCEPROP 1 LAST BODY_TYPE PLUMBING
J 0
(-6175 2500);
DISPLAY 0.872340 (-6175 2500);
PAINT GREEN (-6175 2500);
DISPLAY INVISIBLE (-6175 2500);
FORCEPROP 1 LAST HDL_TAP TRUE
J 0
(-5850 2325);
DISPLAY 0.872340 (-5850 2325);
DISPLAY INVISIBLE (-5850 2325);
FORCEPROP 1 LAST PATH I55
J 0
(-6177 2450);
DISPLAY 0.872340 (-6177 2450);
PAINT GREEN (-6177 2450);
DISPLAY INVISIBLE (-6177 2450);
FORCEADD TAP..1
(-6175 2500);
FORCEPROP 3 LASTPIN (-6225 2500) SIG_NAME M_E_CPU1_SB_DQ<1>
J 0
(-6215 2510);
DISPLAY 0.659574 (-6215 2510);
PAINT MONO (-6215 2510);
DISPLAY INVISIBLE (-6215 2510);
FORCEPROP 1 LASTPIN (-6225 2500) BN 1
J 0
(-6237 2508);
DISPLAY 0.489362 (-6237 2508);
PAINT GREEN (-6237 2508);
FORCEPROP 2 LAST CDS_LIB mstr_standard
J 0
(-6175 2500);
DISPLAY 0.723404 (-6175 2500);
PAINT MONO (-6175 2500);
DISPLAY INVISIBLE (-6175 2500);
FORCEPROP 1 LAST BODY_TYPE PLUMBING
J 0
(-6175 2550);
DISPLAY 0.872340 (-6175 2550);
PAINT GREEN (-6175 2550);
DISPLAY INVISIBLE (-6175 2550);
FORCEPROP 1 LAST HDL_TAP TRUE
J 0
(-5850 2375);
DISPLAY 0.872340 (-5850 2375);
DISPLAY INVISIBLE (-5850 2375);
FORCEPROP 1 LAST PATH I56
J 0
(-6177 2500);
DISPLAY 0.872340 (-6177 2500);
PAINT GREEN (-6177 2500);
DISPLAY INVISIBLE (-6177 2500);
FORCEADD TAP..1
(-6175 2650);
FORCEPROP 3 LASTPIN (-6225 2650) SIG_NAME M_E_CPU1_SB_DQ<4>
J 0
(-6215 2660);
DISPLAY 0.659574 (-6215 2660);
PAINT MONO (-6215 2660);
DISPLAY INVISIBLE (-6215 2660);
FORCEPROP 1 LASTPIN (-6225 2650) BN 4
J 0
(-6237 2658);
DISPLAY 0.489362 (-6237 2658);
PAINT GREEN (-6237 2658);
FORCEPROP 2 LAST CDS_LIB mstr_standard
J 0
(-6175 2650);
DISPLAY 0.723404 (-6175 2650);
PAINT MONO (-6175 2650);
DISPLAY INVISIBLE (-6175 2650);
FORCEPROP 1 LAST BODY_TYPE PLUMBING
J 0
(-6175 2700);
DISPLAY 0.872340 (-6175 2700);
PAINT GREEN (-6175 2700);
DISPLAY INVISIBLE (-6175 2700);
FORCEPROP 1 LAST HDL_TAP TRUE
J 0
(-5850 2525);
DISPLAY 0.872340 (-5850 2525);
DISPLAY INVISIBLE (-5850 2525);
FORCEPROP 1 LAST PATH I57
J 0
(-6177 2650);
DISPLAY 0.872340 (-6177 2650);
PAINT GREEN (-6177 2650);
DISPLAY INVISIBLE (-6177 2650);
FORCEADD TAP..1
(-6175 2700);
FORCEPROP 3 LASTPIN (-6225 2700) SIG_NAME M_E_CPU1_SB_DQ<5>
J 0
(-6215 2710);
DISPLAY 0.659574 (-6215 2710);
PAINT MONO (-6215 2710);
DISPLAY INVISIBLE (-6215 2710);
FORCEPROP 1 LASTPIN (-6225 2700) BN 5
J 0
(-6237 2708);
DISPLAY 0.489362 (-6237 2708);
PAINT GREEN (-6237 2708);
FORCEPROP 2 LAST CDS_LIB mstr_standard
J 0
(-6175 2700);
DISPLAY 0.723404 (-6175 2700);
PAINT MONO (-6175 2700);
DISPLAY INVISIBLE (-6175 2700);
FORCEPROP 1 LAST BODY_TYPE PLUMBING
J 0
(-6175 2750);
DISPLAY 0.872340 (-6175 2750);
PAINT GREEN (-6175 2750);
DISPLAY INVISIBLE (-6175 2750);
FORCEPROP 1 LAST HDL_TAP TRUE
J 0
(-5850 2575);
DISPLAY 0.872340 (-5850 2575);
DISPLAY INVISIBLE (-5850 2575);
FORCEPROP 1 LAST PATH I58
J 0
(-6177 2700);
DISPLAY 0.872340 (-6177 2700);
PAINT GREEN (-6177 2700);
DISPLAY INVISIBLE (-6177 2700);
FORCEADD TAP..1
(-6175 2750);
FORCEPROP 3 LASTPIN (-6225 2750) SIG_NAME M_E_CPU1_SB_DQ<6>
J 0
(-6215 2760);
DISPLAY 0.659574 (-6215 2760);
PAINT MONO (-6215 2760);
DISPLAY INVISIBLE (-6215 2760);
FORCEPROP 1 LASTPIN (-6225 2750) BN 6
J 0
(-6237 2758);
DISPLAY 0.489362 (-6237 2758);
PAINT GREEN (-6237 2758);
FORCEPROP 2 LAST CDS_LIB mstr_standard
J 0
(-6175 2750);
DISPLAY 0.723404 (-6175 2750);
PAINT MONO (-6175 2750);
DISPLAY INVISIBLE (-6175 2750);
FORCEPROP 1 LAST BODY_TYPE PLUMBING
J 0
(-6175 2800);
DISPLAY 0.872340 (-6175 2800);
PAINT GREEN (-6175 2800);
DISPLAY INVISIBLE (-6175 2800);
FORCEPROP 1 LAST HDL_TAP TRUE
J 0
(-5850 2625);
DISPLAY 0.872340 (-5850 2625);
DISPLAY INVISIBLE (-5850 2625);
FORCEPROP 1 LAST PATH I59
J 0
(-6177 2750);
DISPLAY 0.872340 (-6177 2750);
PAINT GREEN (-6177 2750);
DISPLAY INVISIBLE (-6177 2750);
FORCEADD TAP..1
(-6175 2800);
FORCEPROP 3 LASTPIN (-6225 2800) SIG_NAME M_E_CPU1_SB_DQ<7>
J 0
(-6215 2810);
DISPLAY 0.659574 (-6215 2810);
PAINT MONO (-6215 2810);
DISPLAY INVISIBLE (-6215 2810);
FORCEPROP 1 LASTPIN (-6225 2800) BN 7
J 0
(-6237 2808);
DISPLAY 0.489362 (-6237 2808);
PAINT GREEN (-6237 2808);
FORCEPROP 2 LAST CDS_LIB mstr_standard
J 0
(-6175 2800);
DISPLAY 0.723404 (-6175 2800);
PAINT MONO (-6175 2800);
DISPLAY INVISIBLE (-6175 2800);
FORCEPROP 1 LAST BODY_TYPE PLUMBING
J 0
(-6175 2850);
DISPLAY 0.872340 (-6175 2850);
PAINT GREEN (-6175 2850);
DISPLAY INVISIBLE (-6175 2850);
FORCEPROP 1 LAST HDL_TAP TRUE
J 0
(-5850 2675);
DISPLAY 0.872340 (-5850 2675);
DISPLAY INVISIBLE (-5850 2675);
FORCEPROP 1 LAST PATH I60
J 0
(-6177 2800);
DISPLAY 0.872340 (-6177 2800);
PAINT GREEN (-6177 2800);
DISPLAY INVISIBLE (-6177 2800);
FORCEADD TAP..1
(-6175 2850);
FORCEPROP 3 LASTPIN (-6225 2850) SIG_NAME M_E_CPU1_SB_DQ<8>
J 0
(-6215 2860);
DISPLAY 0.659574 (-6215 2860);
PAINT MONO (-6215 2860);
DISPLAY INVISIBLE (-6215 2860);
FORCEPROP 1 LASTPIN (-6225 2850) BN 8
J 0
(-6237 2858);
DISPLAY 0.489362 (-6237 2858);
PAINT GREEN (-6237 2858);
FORCEPROP 2 LAST CDS_LIB mstr_standard
J 0
(-6175 2850);
DISPLAY 0.723404 (-6175 2850);
PAINT MONO (-6175 2850);
DISPLAY INVISIBLE (-6175 2850);
FORCEPROP 1 LAST BODY_TYPE PLUMBING
J 0
(-6175 2900);
DISPLAY 0.872340 (-6175 2900);
PAINT GREEN (-6175 2900);
DISPLAY INVISIBLE (-6175 2900);
FORCEPROP 1 LAST HDL_TAP TRUE
J 0
(-5850 2725);
DISPLAY 0.872340 (-5850 2725);
DISPLAY INVISIBLE (-5850 2725);
FORCEPROP 1 LAST PATH I61
J 0
(-6177 2850);
DISPLAY 0.872340 (-6177 2850);
PAINT GREEN (-6177 2850);
DISPLAY INVISIBLE (-6177 2850);
FORCEADD TAP..1
(-6175 2900);
FORCEPROP 3 LASTPIN (-6225 2900) SIG_NAME M_E_CPU1_SB_DQ<9>
J 0
(-6215 2910);
DISPLAY 0.659574 (-6215 2910);
PAINT MONO (-6215 2910);
DISPLAY INVISIBLE (-6215 2910);
FORCEPROP 1 LASTPIN (-6225 2900) BN 9
J 0
(-6237 2908);
DISPLAY 0.489362 (-6237 2908);
PAINT GREEN (-6237 2908);
FORCEPROP 2 LAST CDS_LIB mstr_standard
J 0
(-6175 2900);
DISPLAY 0.723404 (-6175 2900);
PAINT MONO (-6175 2900);
DISPLAY INVISIBLE (-6175 2900);
FORCEPROP 1 LAST BODY_TYPE PLUMBING
J 0
(-6175 2950);
DISPLAY 0.872340 (-6175 2950);
PAINT GREEN (-6175 2950);
DISPLAY INVISIBLE (-6175 2950);
FORCEPROP 1 LAST HDL_TAP TRUE
J 0
(-5850 2775);
DISPLAY 0.872340 (-5850 2775);
DISPLAY INVISIBLE (-5850 2775);
FORCEPROP 1 LAST PATH I62
J 0
(-6177 2900);
DISPLAY 0.872340 (-6177 2900);
PAINT GREEN (-6177 2900);
DISPLAY INVISIBLE (-6177 2900);
FORCEADD TAP..1
(-6175 2950);
FORCEPROP 3 LASTPIN (-6225 2950) SIG_NAME M_E_CPU1_SB_DQ<10>
J 0
(-6215 2960);
DISPLAY 0.659574 (-6215 2960);
PAINT MONO (-6215 2960);
DISPLAY INVISIBLE (-6215 2960);
FORCEPROP 1 LASTPIN (-6225 2950) BN 10
J 0
(-6237 2958);
DISPLAY 0.489362 (-6237 2958);
PAINT GREEN (-6237 2958);
FORCEPROP 2 LAST CDS_LIB mstr_standard
J 0
(-6175 2950);
DISPLAY 0.723404 (-6175 2950);
PAINT MONO (-6175 2950);
DISPLAY INVISIBLE (-6175 2950);
FORCEPROP 1 LAST BODY_TYPE PLUMBING
J 0
(-6175 3000);
DISPLAY 0.872340 (-6175 3000);
PAINT GREEN (-6175 3000);
DISPLAY INVISIBLE (-6175 3000);
FORCEPROP 1 LAST HDL_TAP TRUE
J 0
(-5850 2825);
DISPLAY 0.872340 (-5850 2825);
DISPLAY INVISIBLE (-5850 2825);
FORCEPROP 1 LAST PATH I63
J 0
(-6177 2950);
DISPLAY 0.872340 (-6177 2950);
PAINT GREEN (-6177 2950);
DISPLAY INVISIBLE (-6177 2950);
FORCEADD TAP..1
(-6175 3000);
FORCEPROP 3 LASTPIN (-6225 3000) SIG_NAME M_E_CPU1_SB_DQ<11>
J 0
(-6215 3010);
DISPLAY 0.659574 (-6215 3010);
PAINT MONO (-6215 3010);
DISPLAY INVISIBLE (-6215 3010);
FORCEPROP 1 LASTPIN (-6225 3000) BN 11
J 0
(-6237 3008);
DISPLAY 0.489362 (-6237 3008);
PAINT GREEN (-6237 3008);
FORCEPROP 2 LAST CDS_LIB mstr_standard
J 0
(-6175 3000);
DISPLAY 0.723404 (-6175 3000);
PAINT MONO (-6175 3000);
DISPLAY INVISIBLE (-6175 3000);
FORCEPROP 1 LAST BODY_TYPE PLUMBING
J 0
(-6175 3050);
DISPLAY 0.872340 (-6175 3050);
PAINT GREEN (-6175 3050);
DISPLAY INVISIBLE (-6175 3050);
FORCEPROP 1 LAST HDL_TAP TRUE
J 0
(-5850 2875);
DISPLAY 0.872340 (-5850 2875);
DISPLAY INVISIBLE (-5850 2875);
FORCEPROP 1 LAST PATH I64
J 0
(-6177 3000);
DISPLAY 0.872340 (-6177 3000);
PAINT GREEN (-6177 3000);
DISPLAY INVISIBLE (-6177 3000);
FORCEADD TAP..1
(-6175 3100);
FORCEPROP 3 LASTPIN (-6225 3100) SIG_NAME M_E_CPU1_SB_DQ<13>
J 0
(-6215 3110);
DISPLAY 0.659574 (-6215 3110);
PAINT MONO (-6215 3110);
DISPLAY INVISIBLE (-6215 3110);
FORCEPROP 1 LASTPIN (-6225 3100) BN 13
J 0
(-6237 3108);
DISPLAY 0.489362 (-6237 3108);
PAINT GREEN (-6237 3108);
FORCEPROP 2 LAST CDS_LIB mstr_standard
J 0
(-6175 3100);
DISPLAY 0.723404 (-6175 3100);
PAINT MONO (-6175 3100);
DISPLAY INVISIBLE (-6175 3100);
FORCEPROP 1 LAST BODY_TYPE PLUMBING
J 0
(-6175 3150);
DISPLAY 0.872340 (-6175 3150);
PAINT GREEN (-6175 3150);
DISPLAY INVISIBLE (-6175 3150);
FORCEPROP 1 LAST HDL_TAP TRUE
J 0
(-5850 2975);
DISPLAY 0.872340 (-5850 2975);
DISPLAY INVISIBLE (-5850 2975);
FORCEPROP 1 LAST PATH I65
J 0
(-6177 3100);
DISPLAY 0.872340 (-6177 3100);
PAINT GREEN (-6177 3100);
DISPLAY INVISIBLE (-6177 3100);
FORCEADD TAP..1
(-6175 3050);
FORCEPROP 3 LASTPIN (-6225 3050) SIG_NAME M_E_CPU1_SB_DQ<12>
J 0
(-6215 3060);
DISPLAY 0.659574 (-6215 3060);
PAINT MONO (-6215 3060);
DISPLAY INVISIBLE (-6215 3060);
FORCEPROP 1 LASTPIN (-6225 3050) BN 12
J 0
(-6237 3058);
DISPLAY 0.489362 (-6237 3058);
PAINT GREEN (-6237 3058);
FORCEPROP 2 LAST CDS_LIB mstr_standard
J 0
(-6175 3050);
DISPLAY 0.723404 (-6175 3050);
PAINT MONO (-6175 3050);
DISPLAY INVISIBLE (-6175 3050);
FORCEPROP 1 LAST BODY_TYPE PLUMBING
J 0
(-6175 3100);
DISPLAY 0.872340 (-6175 3100);
PAINT GREEN (-6175 3100);
DISPLAY INVISIBLE (-6175 3100);
FORCEPROP 1 LAST HDL_TAP TRUE
J 0
(-5850 2925);
DISPLAY 0.872340 (-5850 2925);
DISPLAY INVISIBLE (-5850 2925);
FORCEPROP 1 LAST PATH I66
J 0
(-6177 3050);
DISPLAY 0.872340 (-6177 3050);
PAINT GREEN (-6177 3050);
DISPLAY INVISIBLE (-6177 3050);
FORCEADD TAP..1
(-6175 3200);
FORCEPROP 3 LASTPIN (-6225 3200) SIG_NAME M_E_CPU1_SB_DQ<15>
J 0
(-6215 3210);
DISPLAY 0.659574 (-6215 3210);
PAINT MONO (-6215 3210);
DISPLAY INVISIBLE (-6215 3210);
FORCEPROP 1 LASTPIN (-6225 3200) BN 15
J 0
(-6237 3208);
DISPLAY 0.489362 (-6237 3208);
PAINT GREEN (-6237 3208);
FORCEPROP 2 LAST CDS_LIB mstr_standard
J 0
(-6175 3200);
DISPLAY 0.723404 (-6175 3200);
PAINT MONO (-6175 3200);
DISPLAY INVISIBLE (-6175 3200);
FORCEPROP 1 LAST BODY_TYPE PLUMBING
J 0
(-6175 3250);
DISPLAY 0.872340 (-6175 3250);
PAINT GREEN (-6175 3250);
DISPLAY INVISIBLE (-6175 3250);
FORCEPROP 1 LAST HDL_TAP TRUE
J 0
(-5850 3075);
DISPLAY 0.872340 (-5850 3075);
DISPLAY INVISIBLE (-5850 3075);
FORCEPROP 1 LAST PATH I67
J 0
(-6177 3200);
DISPLAY 0.872340 (-6177 3200);
PAINT GREEN (-6177 3200);
DISPLAY INVISIBLE (-6177 3200);
FORCEADD TAP..1
(-6175 3150);
FORCEPROP 3 LASTPIN (-6225 3150) SIG_NAME M_E_CPU1_SB_DQ<14>
J 0
(-6215 3160);
DISPLAY 0.659574 (-6215 3160);
PAINT MONO (-6215 3160);
DISPLAY INVISIBLE (-6215 3160);
FORCEPROP 1 LASTPIN (-6225 3150) BN 14
J 0
(-6237 3158);
DISPLAY 0.489362 (-6237 3158);
PAINT GREEN (-6237 3158);
FORCEPROP 2 LAST CDS_LIB mstr_standard
J 0
(-6175 3150);
DISPLAY 0.723404 (-6175 3150);
PAINT MONO (-6175 3150);
DISPLAY INVISIBLE (-6175 3150);
FORCEPROP 1 LAST BODY_TYPE PLUMBING
J 0
(-6175 3200);
DISPLAY 0.872340 (-6175 3200);
PAINT GREEN (-6175 3200);
DISPLAY INVISIBLE (-6175 3200);
FORCEPROP 1 LAST HDL_TAP TRUE
J 0
(-5850 3025);
DISPLAY 0.872340 (-5850 3025);
DISPLAY INVISIBLE (-5850 3025);
FORCEPROP 1 LAST PATH I68
J 0
(-6177 3150);
DISPLAY 0.872340 (-6177 3150);
PAINT GREEN (-6177 3150);
DISPLAY INVISIBLE (-6177 3150);
FORCEADD TAP..1
(-6175 3250);
FORCEPROP 3 LASTPIN (-6225 3250) SIG_NAME M_E_CPU1_SB_DQ<16>
J 0
(-6215 3260);
DISPLAY 0.659574 (-6215 3260);
PAINT MONO (-6215 3260);
DISPLAY INVISIBLE (-6215 3260);
FORCEPROP 1 LASTPIN (-6225 3250) BN 16
J 0
(-6237 3258);
DISPLAY 0.489362 (-6237 3258);
PAINT GREEN (-6237 3258);
FORCEPROP 2 LAST CDS_LIB mstr_standard
J 0
(-6175 3250);
DISPLAY 0.723404 (-6175 3250);
PAINT MONO (-6175 3250);
DISPLAY INVISIBLE (-6175 3250);
FORCEPROP 1 LAST BODY_TYPE PLUMBING
J 0
(-6175 3300);
DISPLAY 0.872340 (-6175 3300);
PAINT GREEN (-6175 3300);
DISPLAY INVISIBLE (-6175 3300);
FORCEPROP 1 LAST HDL_TAP TRUE
J 0
(-5850 3125);
DISPLAY 0.872340 (-5850 3125);
DISPLAY INVISIBLE (-5850 3125);
FORCEPROP 1 LAST PATH I69
J 0
(-6177 3250);
DISPLAY 0.872340 (-6177 3250);
PAINT GREEN (-6177 3250);
DISPLAY INVISIBLE (-6177 3250);
FORCEADD OFFPAGE..1
(-8675 3150);
FORCEPROP 2 LAST $XR0 102 
J 0
(-8927 3150);
DISPLAY 0.638298 (-8927 3150);
PAINT MONO (-8927 3150);
FORCEPROP 2 LAST CDS_LIB mstr_standard
J 0
(-8675 3150);
DISPLAY 0.808511 (-8675 3150);
DISPLAY INVISIBLE (-8675 3150);
FORCEPROP 1 LAST OFFPAGE TRUE
J 0
(-8350 3025);
DISPLAY 0.872340 (-8350 3025);
PAINT GREEN (-8350 3025);
DISPLAY INVISIBLE (-8350 3025);
FORCEPROP 1 LAST COMMENT_BODY TRUE
J 0
(-8550 3050);
DISPLAY 0.872340 (-8550 3050);
PAINT GREEN (-8550 3050);
DISPLAY INVISIBLE (-8550 3050);
FORCEPROP 2 LAST PATH I7
J 0
(-8950 3200);
DISPLAY 1.021277 (-8950 3200);
DISPLAY INVISIBLE (-8950 3200);
FORCEADD TAP..1
(-6175 3350);
FORCEPROP 3 LASTPIN (-6225 3350) SIG_NAME M_E_CPU1_SB_DQ<18>
J 0
(-6215 3360);
DISPLAY 0.659574 (-6215 3360);
PAINT MONO (-6215 3360);
DISPLAY INVISIBLE (-6215 3360);
FORCEPROP 1 LASTPIN (-6225 3350) BN 18
J 0
(-6237 3358);
DISPLAY 0.489362 (-6237 3358);
PAINT GREEN (-6237 3358);
FORCEPROP 2 LAST CDS_LIB mstr_standard
J 0
(-6175 3350);
DISPLAY 0.723404 (-6175 3350);
PAINT MONO (-6175 3350);
DISPLAY INVISIBLE (-6175 3350);
FORCEPROP 1 LAST BODY_TYPE PLUMBING
J 0
(-6175 3400);
DISPLAY 0.872340 (-6175 3400);
PAINT GREEN (-6175 3400);
DISPLAY INVISIBLE (-6175 3400);
FORCEPROP 1 LAST HDL_TAP TRUE
J 0
(-5850 3225);
DISPLAY 0.872340 (-5850 3225);
DISPLAY INVISIBLE (-5850 3225);
FORCEPROP 1 LAST PATH I70
J 0
(-6177 3350);
DISPLAY 0.872340 (-6177 3350);
PAINT GREEN (-6177 3350);
DISPLAY INVISIBLE (-6177 3350);
FORCEADD TAP..1
(-6175 3400);
FORCEPROP 3 LASTPIN (-6225 3400) SIG_NAME M_E_CPU1_SB_DQ<19>
J 0
(-6215 3410);
DISPLAY 0.659574 (-6215 3410);
PAINT MONO (-6215 3410);
DISPLAY INVISIBLE (-6215 3410);
FORCEPROP 1 LASTPIN (-6225 3400) BN 19
J 0
(-6237 3408);
DISPLAY 0.489362 (-6237 3408);
PAINT GREEN (-6237 3408);
FORCEPROP 2 LAST CDS_LIB mstr_standard
J 0
(-6175 3400);
DISPLAY 0.723404 (-6175 3400);
PAINT MONO (-6175 3400);
DISPLAY INVISIBLE (-6175 3400);
FORCEPROP 1 LAST BODY_TYPE PLUMBING
J 0
(-6175 3450);
DISPLAY 0.872340 (-6175 3450);
PAINT GREEN (-6175 3450);
DISPLAY INVISIBLE (-6175 3450);
FORCEPROP 1 LAST HDL_TAP TRUE
J 0
(-5850 3275);
DISPLAY 0.872340 (-5850 3275);
DISPLAY INVISIBLE (-5850 3275);
FORCEPROP 1 LAST PATH I71
J 0
(-6177 3400);
DISPLAY 0.872340 (-6177 3400);
PAINT GREEN (-6177 3400);
DISPLAY INVISIBLE (-6177 3400);
FORCEADD TAP..1
(-6175 3300);
FORCEPROP 3 LASTPIN (-6225 3300) SIG_NAME M_E_CPU1_SB_DQ<17>
J 0
(-6215 3310);
DISPLAY 0.659574 (-6215 3310);
PAINT MONO (-6215 3310);
DISPLAY INVISIBLE (-6215 3310);
FORCEPROP 1 LASTPIN (-6225 3300) BN 17
J 0
(-6237 3308);
DISPLAY 0.489362 (-6237 3308);
PAINT GREEN (-6237 3308);
FORCEPROP 2 LAST CDS_LIB mstr_standard
J 0
(-6175 3300);
DISPLAY 0.723404 (-6175 3300);
PAINT MONO (-6175 3300);
DISPLAY INVISIBLE (-6175 3300);
FORCEPROP 1 LAST BODY_TYPE PLUMBING
J 0
(-6175 3350);
DISPLAY 0.872340 (-6175 3350);
PAINT GREEN (-6175 3350);
DISPLAY INVISIBLE (-6175 3350);
FORCEPROP 1 LAST HDL_TAP TRUE
J 0
(-5850 3175);
DISPLAY 0.872340 (-5850 3175);
DISPLAY INVISIBLE (-5850 3175);
FORCEPROP 1 LAST PATH I72
J 0
(-6177 3300);
DISPLAY 0.872340 (-6177 3300);
PAINT GREEN (-6177 3300);
DISPLAY INVISIBLE (-6177 3300);
FORCEADD TAP..1
(-6175 3500);
FORCEPROP 3 LASTPIN (-6225 3500) SIG_NAME M_E_CPU1_SB_DQ<21>
J 0
(-6215 3510);
DISPLAY 0.659574 (-6215 3510);
PAINT MONO (-6215 3510);
DISPLAY INVISIBLE (-6215 3510);
FORCEPROP 1 LASTPIN (-6225 3500) BN 21
J 0
(-6237 3508);
DISPLAY 0.489362 (-6237 3508);
PAINT GREEN (-6237 3508);
FORCEPROP 2 LAST CDS_LIB mstr_standard
J 0
(-6175 3500);
DISPLAY 0.723404 (-6175 3500);
PAINT MONO (-6175 3500);
DISPLAY INVISIBLE (-6175 3500);
FORCEPROP 1 LAST BODY_TYPE PLUMBING
J 0
(-6175 3550);
DISPLAY 0.872340 (-6175 3550);
PAINT GREEN (-6175 3550);
DISPLAY INVISIBLE (-6175 3550);
FORCEPROP 1 LAST HDL_TAP TRUE
J 0
(-5850 3375);
DISPLAY 0.872340 (-5850 3375);
DISPLAY INVISIBLE (-5850 3375);
FORCEPROP 1 LAST PATH I73
J 0
(-6177 3500);
DISPLAY 0.872340 (-6177 3500);
PAINT GREEN (-6177 3500);
DISPLAY INVISIBLE (-6177 3500);
FORCEADD TAP..1
(-6175 3450);
FORCEPROP 3 LASTPIN (-6225 3450) SIG_NAME M_E_CPU1_SB_DQ<20>
J 0
(-6215 3460);
DISPLAY 0.659574 (-6215 3460);
PAINT MONO (-6215 3460);
DISPLAY INVISIBLE (-6215 3460);
FORCEPROP 1 LASTPIN (-6225 3450) BN 20
J 0
(-6237 3458);
DISPLAY 0.489362 (-6237 3458);
PAINT GREEN (-6237 3458);
FORCEPROP 2 LAST CDS_LIB mstr_standard
J 0
(-6175 3450);
DISPLAY 0.723404 (-6175 3450);
PAINT MONO (-6175 3450);
DISPLAY INVISIBLE (-6175 3450);
FORCEPROP 1 LAST BODY_TYPE PLUMBING
J 0
(-6175 3500);
DISPLAY 0.872340 (-6175 3500);
PAINT GREEN (-6175 3500);
DISPLAY INVISIBLE (-6175 3500);
FORCEPROP 1 LAST HDL_TAP TRUE
J 0
(-5850 3325);
DISPLAY 0.872340 (-5850 3325);
DISPLAY INVISIBLE (-5850 3325);
FORCEPROP 1 LAST PATH I74
J 0
(-6177 3450);
DISPLAY 0.872340 (-6177 3450);
PAINT GREEN (-6177 3450);
DISPLAY INVISIBLE (-6177 3450);
FORCEADD TAP..1
(-6175 3550);
FORCEPROP 3 LASTPIN (-6225 3550) SIG_NAME M_E_CPU1_SB_DQ<22>
J 0
(-6215 3560);
DISPLAY 0.659574 (-6215 3560);
PAINT MONO (-6215 3560);
DISPLAY INVISIBLE (-6215 3560);
FORCEPROP 1 LASTPIN (-6225 3550) BN 22
J 0
(-6237 3558);
DISPLAY 0.489362 (-6237 3558);
PAINT GREEN (-6237 3558);
FORCEPROP 2 LAST CDS_LIB mstr_standard
J 0
(-6175 3550);
DISPLAY 0.723404 (-6175 3550);
PAINT MONO (-6175 3550);
DISPLAY INVISIBLE (-6175 3550);
FORCEPROP 1 LAST BODY_TYPE PLUMBING
J 0
(-6175 3600);
DISPLAY 0.872340 (-6175 3600);
PAINT GREEN (-6175 3600);
DISPLAY INVISIBLE (-6175 3600);
FORCEPROP 1 LAST HDL_TAP TRUE
J 0
(-5850 3425);
DISPLAY 0.872340 (-5850 3425);
DISPLAY INVISIBLE (-5850 3425);
FORCEPROP 1 LAST PATH I75
J 0
(-6177 3550);
DISPLAY 0.872340 (-6177 3550);
PAINT GREEN (-6177 3550);
DISPLAY INVISIBLE (-6177 3550);
FORCEADD TAP..1
(-6175 3650);
FORCEPROP 3 LASTPIN (-6225 3650) SIG_NAME M_E_CPU1_SB_DQ<24>
J 0
(-6215 3660);
DISPLAY 0.659574 (-6215 3660);
PAINT MONO (-6215 3660);
DISPLAY INVISIBLE (-6215 3660);
FORCEPROP 1 LASTPIN (-6225 3650) BN 24
J 0
(-6237 3658);
DISPLAY 0.489362 (-6237 3658);
PAINT GREEN (-6237 3658);
FORCEPROP 2 LAST CDS_LIB mstr_standard
J 0
(-6175 3650);
DISPLAY 0.723404 (-6175 3650);
PAINT MONO (-6175 3650);
DISPLAY INVISIBLE (-6175 3650);
FORCEPROP 1 LAST BODY_TYPE PLUMBING
J 0
(-6175 3700);
DISPLAY 0.872340 (-6175 3700);
PAINT GREEN (-6175 3700);
DISPLAY INVISIBLE (-6175 3700);
FORCEPROP 1 LAST HDL_TAP TRUE
J 0
(-5850 3525);
DISPLAY 0.872340 (-5850 3525);
DISPLAY INVISIBLE (-5850 3525);
FORCEPROP 1 LAST PATH I76
J 0
(-6177 3650);
DISPLAY 0.872340 (-6177 3650);
PAINT GREEN (-6177 3650);
DISPLAY INVISIBLE (-6177 3650);
FORCEADD TAP..1
(-6175 3600);
FORCEPROP 3 LASTPIN (-6225 3600) SIG_NAME M_E_CPU1_SB_DQ<23>
J 0
(-6215 3610);
DISPLAY 0.659574 (-6215 3610);
PAINT MONO (-6215 3610);
DISPLAY INVISIBLE (-6215 3610);
FORCEPROP 1 LASTPIN (-6225 3600) BN 23
J 0
(-6237 3608);
DISPLAY 0.489362 (-6237 3608);
PAINT GREEN (-6237 3608);
FORCEPROP 2 LAST CDS_LIB mstr_standard
J 0
(-6175 3600);
DISPLAY 0.723404 (-6175 3600);
PAINT MONO (-6175 3600);
DISPLAY INVISIBLE (-6175 3600);
FORCEPROP 1 LAST BODY_TYPE PLUMBING
J 0
(-6175 3650);
DISPLAY 0.872340 (-6175 3650);
PAINT GREEN (-6175 3650);
DISPLAY INVISIBLE (-6175 3650);
FORCEPROP 1 LAST HDL_TAP TRUE
J 0
(-5850 3475);
DISPLAY 0.872340 (-5850 3475);
DISPLAY INVISIBLE (-5850 3475);
FORCEPROP 1 LAST PATH I77
J 0
(-6177 3600);
DISPLAY 0.872340 (-6177 3600);
PAINT GREEN (-6177 3600);
DISPLAY INVISIBLE (-6177 3600);
FORCEADD TAP..1
(-6175 3750);
FORCEPROP 3 LASTPIN (-6225 3750) SIG_NAME M_E_CPU1_SB_DQ<26>
J 0
(-6215 3760);
DISPLAY 0.659574 (-6215 3760);
PAINT MONO (-6215 3760);
DISPLAY INVISIBLE (-6215 3760);
FORCEPROP 1 LASTPIN (-6225 3750) BN 26
J 0
(-6237 3758);
DISPLAY 0.489362 (-6237 3758);
PAINT GREEN (-6237 3758);
FORCEPROP 2 LAST CDS_LIB mstr_standard
J 0
(-6175 3750);
DISPLAY 0.723404 (-6175 3750);
PAINT MONO (-6175 3750);
DISPLAY INVISIBLE (-6175 3750);
FORCEPROP 1 LAST BODY_TYPE PLUMBING
J 0
(-6175 3800);
DISPLAY 0.872340 (-6175 3800);
PAINT GREEN (-6175 3800);
DISPLAY INVISIBLE (-6175 3800);
FORCEPROP 1 LAST HDL_TAP TRUE
J 0
(-5850 3625);
DISPLAY 0.872340 (-5850 3625);
DISPLAY INVISIBLE (-5850 3625);
FORCEPROP 1 LAST PATH I78
J 0
(-6177 3750);
DISPLAY 0.872340 (-6177 3750);
PAINT GREEN (-6177 3750);
DISPLAY INVISIBLE (-6177 3750);
FORCEADD TAP..1
(-6175 3700);
FORCEPROP 3 LASTPIN (-6225 3700) SIG_NAME M_E_CPU1_SB_DQ<25>
J 0
(-6215 3710);
DISPLAY 0.659574 (-6215 3710);
PAINT MONO (-6215 3710);
DISPLAY INVISIBLE (-6215 3710);
FORCEPROP 1 LASTPIN (-6225 3700) BN 25
J 0
(-6237 3708);
DISPLAY 0.489362 (-6237 3708);
PAINT GREEN (-6237 3708);
FORCEPROP 2 LAST CDS_LIB mstr_standard
J 0
(-6175 3700);
DISPLAY 0.723404 (-6175 3700);
PAINT MONO (-6175 3700);
DISPLAY INVISIBLE (-6175 3700);
FORCEPROP 1 LAST BODY_TYPE PLUMBING
J 0
(-6175 3750);
DISPLAY 0.872340 (-6175 3750);
PAINT GREEN (-6175 3750);
DISPLAY INVISIBLE (-6175 3750);
FORCEPROP 1 LAST HDL_TAP TRUE
J 0
(-5850 3575);
DISPLAY 0.872340 (-5850 3575);
DISPLAY INVISIBLE (-5850 3575);
FORCEPROP 1 LAST PATH I79
J 0
(-6177 3700);
DISPLAY 0.872340 (-6177 3700);
PAINT GREEN (-6177 3700);
DISPLAY INVISIBLE (-6177 3700);
FORCEADD OFFPAGE..1
(-8350 3350);
FORCEPROP 2 LAST $XR0 41 
J 0
(-8601 3350);
DISPLAY 0.638298 (-8601 3350);
PAINT MONO (-8601 3350);
FORCEPROP 2 LAST CDS_LIB mstr_standard
J 0
(-8350 3350);
DISPLAY 0.808511 (-8350 3350);
DISPLAY INVISIBLE (-8350 3350);
FORCEPROP 1 LAST OFFPAGE TRUE
J 0
(-8025 3225);
DISPLAY 0.872340 (-8025 3225);
PAINT GREEN (-8025 3225);
DISPLAY INVISIBLE (-8025 3225);
FORCEPROP 1 LAST COMMENT_BODY TRUE
J 0
(-8225 3250);
DISPLAY 0.872340 (-8225 3250);
PAINT GREEN (-8225 3250);
DISPLAY INVISIBLE (-8225 3250);
FORCEPROP 2 LAST PATH I8
J 0
(-8550 3400);
DISPLAY 1.021277 (-8550 3400);
DISPLAY INVISIBLE (-8550 3400);
FORCEADD TAP..1
(-6175 3800);
FORCEPROP 3 LASTPIN (-6225 3800) SIG_NAME M_E_CPU1_SB_DQ<27>
J 0
(-6215 3810);
DISPLAY 0.659574 (-6215 3810);
PAINT MONO (-6215 3810);
DISPLAY INVISIBLE (-6215 3810);
FORCEPROP 1 LASTPIN (-6225 3800) BN 27
J 0
(-6237 3808);
DISPLAY 0.489362 (-6237 3808);
PAINT GREEN (-6237 3808);
FORCEPROP 2 LAST CDS_LIB mstr_standard
J 0
(-6175 3800);
DISPLAY 0.723404 (-6175 3800);
PAINT MONO (-6175 3800);
DISPLAY INVISIBLE (-6175 3800);
FORCEPROP 1 LAST BODY_TYPE PLUMBING
J 0
(-6175 3850);
DISPLAY 0.872340 (-6175 3850);
PAINT GREEN (-6175 3850);
DISPLAY INVISIBLE (-6175 3850);
FORCEPROP 1 LAST HDL_TAP TRUE
J 0
(-5850 3675);
DISPLAY 0.872340 (-5850 3675);
DISPLAY INVISIBLE (-5850 3675);
FORCEPROP 1 LAST PATH I80
J 0
(-6177 3800);
DISPLAY 0.872340 (-6177 3800);
PAINT GREEN (-6177 3800);
DISPLAY INVISIBLE (-6177 3800);
FORCEADD TAP..1
(-6175 3900);
FORCEPROP 3 LASTPIN (-6225 3900) SIG_NAME M_E_CPU1_SB_DQ<29>
J 0
(-6215 3910);
DISPLAY 0.659574 (-6215 3910);
PAINT MONO (-6215 3910);
DISPLAY INVISIBLE (-6215 3910);
FORCEPROP 1 LASTPIN (-6225 3900) BN 29
J 0
(-6237 3908);
DISPLAY 0.489362 (-6237 3908);
PAINT GREEN (-6237 3908);
FORCEPROP 2 LAST CDS_LIB mstr_standard
J 0
(-6175 3900);
DISPLAY 0.723404 (-6175 3900);
PAINT MONO (-6175 3900);
DISPLAY INVISIBLE (-6175 3900);
FORCEPROP 1 LAST BODY_TYPE PLUMBING
J 0
(-6175 3950);
DISPLAY 0.872340 (-6175 3950);
PAINT GREEN (-6175 3950);
DISPLAY INVISIBLE (-6175 3950);
FORCEPROP 1 LAST HDL_TAP TRUE
J 0
(-5850 3775);
DISPLAY 0.872340 (-5850 3775);
DISPLAY INVISIBLE (-5850 3775);
FORCEPROP 1 LAST PATH I81
J 0
(-6177 3900);
DISPLAY 0.872340 (-6177 3900);
PAINT GREEN (-6177 3900);
DISPLAY INVISIBLE (-6177 3900);
FORCEADD TAP..1
(-6175 3850);
FORCEPROP 3 LASTPIN (-6225 3850) SIG_NAME M_E_CPU1_SB_DQ<28>
J 0
(-6215 3860);
DISPLAY 0.659574 (-6215 3860);
PAINT MONO (-6215 3860);
DISPLAY INVISIBLE (-6215 3860);
FORCEPROP 1 LASTPIN (-6225 3850) BN 28
J 0
(-6237 3858);
DISPLAY 0.489362 (-6237 3858);
PAINT GREEN (-6237 3858);
FORCEPROP 2 LAST CDS_LIB mstr_standard
J 0
(-6175 3850);
DISPLAY 0.723404 (-6175 3850);
PAINT MONO (-6175 3850);
DISPLAY INVISIBLE (-6175 3850);
FORCEPROP 1 LAST BODY_TYPE PLUMBING
J 0
(-6175 3900);
DISPLAY 0.872340 (-6175 3900);
PAINT GREEN (-6175 3900);
DISPLAY INVISIBLE (-6175 3900);
FORCEPROP 1 LAST HDL_TAP TRUE
J 0
(-5850 3725);
DISPLAY 0.872340 (-5850 3725);
DISPLAY INVISIBLE (-5850 3725);
FORCEPROP 1 LAST PATH I82
J 0
(-6177 3850);
DISPLAY 0.872340 (-6177 3850);
PAINT GREEN (-6177 3850);
DISPLAY INVISIBLE (-6177 3850);
FORCEADD TAP..1
(-6175 3950);
FORCEPROP 3 LASTPIN (-6225 3950) SIG_NAME M_E_CPU1_SB_DQ<30>
J 0
(-6215 3960);
DISPLAY 0.659574 (-6215 3960);
PAINT MONO (-6215 3960);
DISPLAY INVISIBLE (-6215 3960);
FORCEPROP 1 LASTPIN (-6225 3950) BN 30
J 0
(-6237 3958);
DISPLAY 0.489362 (-6237 3958);
PAINT GREEN (-6237 3958);
FORCEPROP 2 LAST CDS_LIB mstr_standard
J 0
(-6175 3950);
DISPLAY 0.723404 (-6175 3950);
PAINT MONO (-6175 3950);
DISPLAY INVISIBLE (-6175 3950);
FORCEPROP 1 LAST BODY_TYPE PLUMBING
J 0
(-6175 4000);
DISPLAY 0.872340 (-6175 4000);
PAINT GREEN (-6175 4000);
DISPLAY INVISIBLE (-6175 4000);
FORCEPROP 1 LAST HDL_TAP TRUE
J 0
(-5850 3825);
DISPLAY 0.872340 (-5850 3825);
DISPLAY INVISIBLE (-5850 3825);
FORCEPROP 1 LAST PATH I83
J 0
(-6177 3950);
DISPLAY 0.872340 (-6177 3950);
PAINT GREEN (-6177 3950);
DISPLAY INVISIBLE (-6177 3950);
FORCEADD TAP..1
(-6175 4000);
FORCEPROP 3 LASTPIN (-6225 4000) SIG_NAME M_E_CPU1_SB_DQ<31>
J 0
(-6215 4010);
DISPLAY 0.659574 (-6215 4010);
PAINT MONO (-6215 4010);
DISPLAY INVISIBLE (-6215 4010);
FORCEPROP 1 LASTPIN (-6225 4000) BN 31
J 0
(-6237 4008);
DISPLAY 0.489362 (-6237 4008);
PAINT GREEN (-6237 4008);
FORCEPROP 2 LAST CDS_LIB mstr_standard
J 0
(-6175 4000);
DISPLAY 0.723404 (-6175 4000);
PAINT MONO (-6175 4000);
DISPLAY INVISIBLE (-6175 4000);
FORCEPROP 1 LAST BODY_TYPE PLUMBING
J 0
(-6175 4050);
DISPLAY 0.872340 (-6175 4050);
PAINT GREEN (-6175 4050);
DISPLAY INVISIBLE (-6175 4050);
FORCEPROP 1 LAST HDL_TAP TRUE
J 0
(-5850 3875);
DISPLAY 0.872340 (-5850 3875);
DISPLAY INVISIBLE (-5850 3875);
FORCEPROP 1 LAST PATH I84
J 0
(-6177 4000);
DISPLAY 0.872340 (-6177 4000);
PAINT GREEN (-6177 4000);
DISPLAY INVISIBLE (-6177 4000);
FORCEADD TAP..1
(-6175 4150);
FORCEPROP 3 LASTPIN (-6225 4150) SIG_NAME M_E_CPU1_SA_DQ<1>
J 0
(-6215 4160);
DISPLAY 0.659574 (-6215 4160);
PAINT MONO (-6215 4160);
DISPLAY INVISIBLE (-6215 4160);
FORCEPROP 1 LASTPIN (-6225 4150) BN 1
J 0
(-6237 4158);
DISPLAY 0.489362 (-6237 4158);
PAINT GREEN (-6237 4158);
FORCEPROP 2 LAST CDS_LIB mstr_standard
J 0
(-6175 4150);
DISPLAY 0.723404 (-6175 4150);
PAINT MONO (-6175 4150);
DISPLAY INVISIBLE (-6175 4150);
FORCEPROP 1 LAST BODY_TYPE PLUMBING
J 0
(-6175 4200);
DISPLAY 0.872340 (-6175 4200);
PAINT GREEN (-6175 4200);
DISPLAY INVISIBLE (-6175 4200);
FORCEPROP 1 LAST HDL_TAP TRUE
J 0
(-5850 4025);
DISPLAY 0.872340 (-5850 4025);
DISPLAY INVISIBLE (-5850 4025);
FORCEPROP 1 LAST PATH I85
J 0
(-6177 4150);
DISPLAY 0.872340 (-6177 4150);
PAINT GREEN (-6177 4150);
DISPLAY INVISIBLE (-6177 4150);
FORCEADD TAP..1
(-6175 4100);
FORCEPROP 3 LASTPIN (-6225 4100) SIG_NAME M_E_CPU1_SA_DQ<0>
J 0
(-6215 4110);
DISPLAY 0.659574 (-6215 4110);
PAINT MONO (-6215 4110);
DISPLAY INVISIBLE (-6215 4110);
FORCEPROP 1 LASTPIN (-6225 4100) BN 0
J 0
(-6237 4108);
DISPLAY 0.489362 (-6237 4108);
PAINT GREEN (-6237 4108);
FORCEPROP 2 LAST CDS_LIB mstr_standard
J 0
(-6175 4100);
DISPLAY 0.723404 (-6175 4100);
PAINT MONO (-6175 4100);
DISPLAY INVISIBLE (-6175 4100);
FORCEPROP 1 LAST BODY_TYPE PLUMBING
J 0
(-6175 4150);
DISPLAY 0.872340 (-6175 4150);
PAINT GREEN (-6175 4150);
DISPLAY INVISIBLE (-6175 4150);
FORCEPROP 1 LAST HDL_TAP TRUE
J 0
(-5850 3975);
DISPLAY 0.872340 (-5850 3975);
DISPLAY INVISIBLE (-5850 3975);
FORCEPROP 1 LAST PATH I86
J 0
(-6177 4100);
DISPLAY 0.872340 (-6177 4100);
PAINT GREEN (-6177 4100);
DISPLAY INVISIBLE (-6177 4100);
FORCEADD OFFPAGE..5
(-8350 3300);
FORCEPROP 2 LAST $XR0 41 
J 0
(-8574 3300);
DISPLAY 0.638298 (-8574 3300);
PAINT MONO (-8574 3300);
FORCEPROP 2 LAST CDS_LIB mstr_standard
J 0
(-8350 3300);
DISPLAY INVISIBLE (-8350 3300);
FORCEPROP 1 LAST OFFPAGE TRUE
J 0
(-8025 3175);
DISPLAY 0.872340 (-8025 3175);
PAINT GREEN (-8025 3175);
DISPLAY INVISIBLE (-8025 3175);
FORCEPROP 1 LAST COMMENT_BODY TRUE
J 0
(-8250 3225);
DISPLAY 0.872340 (-8250 3225);
PAINT GREEN (-8250 3225);
DISPLAY INVISIBLE (-8250 3225);
FORCEPROP 2 LAST PATH I9
J 0
(-8600 3350);
DISPLAY 1.021277 (-8600 3350);
DISPLAY INVISIBLE (-8600 3350);
FORCEADD OFFPAGE..3
(-5500 4050);
FORCEPROP 2 LAST $XR0 41 
J 0
(-5286 4050);
DISPLAY 0.638298 (-5286 4050);
PAINT MONO (-5286 4050);
FORCEPROP 2 LAST CDS_LIB mstr_standard
J 0
(-5500 4050);
DISPLAY 0.723404 (-5500 4050);
PAINT MONO (-5500 4050);
DISPLAY INVISIBLE (-5500 4050);
FORCEPROP 1 LAST OFFPAGE TRUE
J 0
(-5175 3925);
DISPLAY 0.872340 (-5175 3925);
PAINT GREEN (-5175 3925);
DISPLAY INVISIBLE (-5175 3925);
FORCEPROP 1 LAST COMMENT_BODY TRUE
J 0
(-5550 3950);
DISPLAY 0.872340 (-5550 3950);
PAINT GREEN (-5550 3950);
DISPLAY INVISIBLE (-5550 3950);
FORCEPROP 2 LAST PATH I93
J 0
(-5275 4100);
DISPLAY 1.021277 (-5275 4100);
DISPLAY INVISIBLE (-5275 4100);
FORCEADD TAP..1
(-6175 4200);
FORCEPROP 3 LASTPIN (-6225 4200) SIG_NAME M_E_CPU1_SA_DQ<2>
J 0
(-6215 4210);
DISPLAY 0.659574 (-6215 4210);
PAINT MONO (-6215 4210);
DISPLAY INVISIBLE (-6215 4210);
FORCEPROP 1 LASTPIN (-6225 4200) BN 2
J 0
(-6237 4208);
DISPLAY 0.489362 (-6237 4208);
PAINT GREEN (-6237 4208);
FORCEPROP 2 LAST CDS_LIB mstr_standard
J 0
(-6175 4200);
DISPLAY 0.723404 (-6175 4200);
PAINT MONO (-6175 4200);
DISPLAY INVISIBLE (-6175 4200);
FORCEPROP 1 LAST BODY_TYPE PLUMBING
J 0
(-6175 4250);
DISPLAY 0.872340 (-6175 4250);
PAINT GREEN (-6175 4250);
DISPLAY INVISIBLE (-6175 4250);
FORCEPROP 1 LAST HDL_TAP TRUE
J 0
(-5850 4075);
DISPLAY 0.872340 (-5850 4075);
DISPLAY INVISIBLE (-5850 4075);
FORCEPROP 1 LAST PATH I95
J 0
(-6177 4200);
DISPLAY 0.872340 (-6177 4200);
PAINT GREEN (-6177 4200);
DISPLAY INVISIBLE (-6177 4200);
FORCEADD TAP..1
(-6175 4250);
FORCEPROP 3 LASTPIN (-6225 4250) SIG_NAME M_E_CPU1_SA_DQ<3>
J 0
(-6215 4260);
DISPLAY 0.659574 (-6215 4260);
PAINT MONO (-6215 4260);
DISPLAY INVISIBLE (-6215 4260);
FORCEPROP 1 LASTPIN (-6225 4250) BN 3
J 0
(-6237 4258);
DISPLAY 0.489362 (-6237 4258);
PAINT GREEN (-6237 4258);
FORCEPROP 2 LAST CDS_LIB mstr_standard
J 0
(-6175 4250);
DISPLAY 0.723404 (-6175 4250);
PAINT MONO (-6175 4250);
DISPLAY INVISIBLE (-6175 4250);
FORCEPROP 1 LAST BODY_TYPE PLUMBING
J 0
(-6175 4300);
DISPLAY 0.872340 (-6175 4300);
PAINT GREEN (-6175 4300);
DISPLAY INVISIBLE (-6175 4300);
FORCEPROP 1 LAST HDL_TAP TRUE
J 0
(-5850 4125);
DISPLAY 0.872340 (-5850 4125);
DISPLAY INVISIBLE (-5850 4125);
FORCEPROP 1 LAST PATH I96
J 0
(-6177 4250);
DISPLAY 0.872340 (-6177 4250);
PAINT GREEN (-6177 4250);
DISPLAY INVISIBLE (-6177 4250);
FORCEADD TAP..1
(-6175 4300);
FORCEPROP 3 LASTPIN (-6225 4300) SIG_NAME M_E_CPU1_SA_DQ<4>
J 0
(-6215 4310);
DISPLAY 0.659574 (-6215 4310);
PAINT MONO (-6215 4310);
DISPLAY INVISIBLE (-6215 4310);
FORCEPROP 1 LASTPIN (-6225 4300) BN 4
J 0
(-6237 4308);
DISPLAY 0.489362 (-6237 4308);
PAINT GREEN (-6237 4308);
FORCEPROP 2 LAST CDS_LIB mstr_standard
J 0
(-6175 4300);
DISPLAY 0.723404 (-6175 4300);
PAINT MONO (-6175 4300);
DISPLAY INVISIBLE (-6175 4300);
FORCEPROP 1 LAST BODY_TYPE PLUMBING
J 0
(-6175 4350);
DISPLAY 0.872340 (-6175 4350);
PAINT GREEN (-6175 4350);
DISPLAY INVISIBLE (-6175 4350);
FORCEPROP 1 LAST HDL_TAP TRUE
J 0
(-5850 4175);
DISPLAY 0.872340 (-5850 4175);
DISPLAY INVISIBLE (-5850 4175);
FORCEPROP 1 LAST PATH I97
J 0
(-6177 4300);
DISPLAY 0.872340 (-6177 4300);
PAINT GREEN (-6177 4300);
DISPLAY INVISIBLE (-6177 4300);
FORCEADD TAP..1
(-6175 4400);
FORCEPROP 3 LASTPIN (-6225 4400) SIG_NAME M_E_CPU1_SA_DQ<6>
J 0
(-6215 4410);
DISPLAY 0.659574 (-6215 4410);
PAINT MONO (-6215 4410);
DISPLAY INVISIBLE (-6215 4410);
FORCEPROP 1 LASTPIN (-6225 4400) BN 6
J 0
(-6237 4408);
DISPLAY 0.489362 (-6237 4408);
PAINT GREEN (-6237 4408);
FORCEPROP 2 LAST CDS_LIB mstr_standard
J 0
(-6175 4400);
DISPLAY 0.723404 (-6175 4400);
PAINT MONO (-6175 4400);
DISPLAY INVISIBLE (-6175 4400);
FORCEPROP 1 LAST BODY_TYPE PLUMBING
J 0
(-6175 4450);
DISPLAY 0.872340 (-6175 4450);
PAINT GREEN (-6175 4450);
DISPLAY INVISIBLE (-6175 4450);
FORCEPROP 1 LAST HDL_TAP TRUE
J 0
(-5850 4275);
DISPLAY 0.872340 (-5850 4275);
DISPLAY INVISIBLE (-5850 4275);
FORCEPROP 1 LAST PATH I98
J 0
(-6177 4400);
DISPLAY 0.872340 (-6177 4400);
PAINT GREEN (-6177 4400);
DISPLAY INVISIBLE (-6177 4400);
FORCEADD TAP..1
(-6175 4350);
FORCEPROP 3 LASTPIN (-6225 4350) SIG_NAME M_E_CPU1_SA_DQ<5>
J 0
(-6215 4360);
DISPLAY 0.659574 (-6215 4360);
PAINT MONO (-6215 4360);
DISPLAY INVISIBLE (-6215 4360);
FORCEPROP 1 LASTPIN (-6225 4350) BN 5
J 0
(-6237 4358);
DISPLAY 0.489362 (-6237 4358);
PAINT GREEN (-6237 4358);
FORCEPROP 2 LAST CDS_LIB mstr_standard
J 0
(-6175 4350);
DISPLAY 0.723404 (-6175 4350);
PAINT MONO (-6175 4350);
DISPLAY INVISIBLE (-6175 4350);
FORCEPROP 1 LAST BODY_TYPE PLUMBING
J 0
(-6175 4400);
DISPLAY 0.872340 (-6175 4400);
PAINT GREEN (-6175 4400);
DISPLAY INVISIBLE (-6175 4400);
FORCEPROP 1 LAST HDL_TAP TRUE
J 0
(-5850 4225);
DISPLAY 0.872340 (-5850 4225);
DISPLAY INVISIBLE (-5850 4225);
FORCEPROP 1 LAST PATH I99
J 0
(-6177 4350);
DISPLAY 0.872340 (-6177 4350);
PAINT GREEN (-6177 4350);
DISPLAY INVISIBLE (-6177 4350);
FORCEADD QUANTA_TITLE_BLOCK_C..1
(-100 100);
FORCEPROP 0 LAST CDS_CON_LAST_MODIFIED Thu Sep 14 16:12:11 2023
J 0
(-1985 115);
DISPLAY INVISIBLE (-1985 115);
FORCEPROP 1 LAST CUSTOM_TXT_CDS <CON_LAST_MODIFIED>
J 0
(-1985 115);
DISPLAY 0.978723 (-1985 115);
FORCEPROP 2 LAST CUSTOM_TXT_CDS <XR_PAGE_TITLE>
J 0
(-7990 5350);
DISPLAY 0.638298 (-7990 5350);
PAINT PINK (-7990 5350);
DISPLAY INVISIBLE (-7990 5350);
FORCEPROP 1 LAST CUSTOM_TXT_CDS <NAME_2>
J 0
(-3275 150);
FORCEPROP 1 LAST CUSTOM_TXT_CDS <NAME_1>
J 0
(-3275 275);
FORCEPROP 1 LAST CUSTOM_TXT_CDS <Q_NUMBER>
J 0
(-1503 203);
DISPLAY 1.212766 (-1503 203);
FORCEPROP 1 LAST CUSTOM_TXT_CDS <Q_PROJ>
J 0
(-2482 202);
DISPLAY 1.212766 (-2482 202);
FORCEPROP 1 LAST CUSTOM_TXT_CDS <Q_REV>
J 0
(-284 203);
DISPLAY 1.212766 (-284 203);
FORCEPROP 1 LAST CUSTOM_TXT_CDS <CON_PAGE_NUM> OF <CON_TOTAL_PAGES>
J 0
(-546 118);
DISPLAY 0.978723 (-546 118);
FORCEPROP 1 LAST Q_TITLE DDR5 - CPU1 CHE
J 0
(-9425 150);
DISPLAY 2.446809 (-9425 150);
PAINT GREEN (-9425 150);
FORCEPROP 2 LAST PAGE_BORDER TRUE
J 0
(-7990 5350);
DISPLAY 0.638298 (-7990 5350);
PAINT PINK (-7990 5350);
DISPLAY INVISIBLE (-7990 5350);
FORCEPROP 2 LAST CDS_LIB pure_quanta
J 0
(-100 100);
DISPLAY INVISIBLE (-100 100);
FORCEPROP 1 LAST CDS_LMAN_SYM_OUTLINE -9475,6775,100,-125
J 0
(-100 100);
DISPLAY 0.468085 (-100 100);
PAINT GREEN (-100 100);
DISPLAY INVISIBLE (-100 100);
FORCEPROP 2 LAST CDS_XR_PAGE_TITLE CR-102 : @T6G_MB_LIB.T6G(SCH_1):PAGE102
J 0
(-7990 5350);
DISPLAY 0.638298 (-7990 5350);
PAINT PINK (-7990 5350);
DISPLAY INVISIBLE (-7990 5350);
FORCEPROP 1 LAST Q_DEPT BU9
J 1
(-3863 149);
DISPLAY 1.957447 (-3863 149);
PAINT GREEN (-3863 149);
DISPLAY INVISIBLE (-3863 149);
FORCEPROP 1 LAST COMMENT_BODY TRUE
J 0
(-88 87);
DISPLAY 0.978723 (-88 87);
PAINT GREEN (-88 87);
DISPLAY INVISIBLE (-88 87);
FORCEADD DNS..2
(-8475 2550);
PAINT RED (-8475 2550);
FORCEPROP 2 LAST CDS_LIB mstr_misc
J 0
(-8475 2550);
DISPLAY INVISIBLE (-8475 2550);
FORCEPROP 1 LAST COMMENT_BODY TRUE
R 1
J 0
(-8400 2325);
DISPLAY 0.872340 (-8400 2325);
PAINT PEACH (-8400 2325);
DISPLAY INVISIBLE (-8400 2325);
WIRE 17 -1 (-7925 3475)(-7925 3525);
WIRE 17 -1 (-7925 3525)(-7925 3575);
WIRE 17 -1 (-7925 3575)(-7925 3625);
WIRE 17 -1 (-7925 3625)(-7925 3675);
WIRE 17 -1 (-7925 3725)(-7925 3675);
WIRE 17 -1 (-7925 3725)(-7925 3775);
WIRE 17 -1 (-7925 3825)(-7925 3775);
WIRE 17 -1 (-7925 3825)(-7925 3850);
WIRE 17 -1 (-7925 3850)(-8425 3850);
FORCEPROP 2 LAST SIG_NAME M_E_CPU1_SB_CB<7:0>
J 0
(-8375 3860);
DISPLAY 0.489362 (-8375 3860);
WIRE 17 -1 (-6125 3075)(-6125 3125);
WIRE 17 -1 (-6125 3075)(-6125 3025);
WIRE 17 -1 (-6125 3125)(-6125 3175);
WIRE 17 -1 (-6125 3175)(-6125 3225);
WIRE 17 -1 (-6125 3025)(-6125 2975);
WIRE 17 -1 (-6125 2975)(-6125 2925);
WIRE 17 -1 (-6125 3225)(-6125 3275);
WIRE 17 -1 (-6125 3325)(-6125 3275);
WIRE 17 -1 (-6125 2925)(-6125 2875);
WIRE 17 -1 (-6125 2875)(-6125 2825);
WIRE 17 -1 (-6125 3375)(-6125 3325);
WIRE 17 -1 (-6125 3425)(-6125 3375);
WIRE 17 -1 (-6125 2825)(-6125 2775);
WIRE 17 -1 (-6125 2775)(-6125 2725);
WIRE 17 -1 (-6125 3475)(-6125 3425);
WIRE 17 -1 (-6125 3525)(-6125 3475);
WIRE 17 -1 (-6125 2725)(-6125 2675);
WIRE 17 -1 (-6125 2625)(-6125 2675);
WIRE 17 -1 (-6125 3575)(-6125 3525);
WIRE 17 -1 (-6125 3625)(-6125 3575);
WIRE 17 -1 (-6125 2575)(-6125 2625);
WIRE 17 -1 (-6125 2525)(-6125 2575);
WIRE 17 -1 (-6125 3675)(-6125 3625);
WIRE 17 -1 (-6125 3725)(-6125 3675);
WIRE 17 -1 (-6125 2475)(-6125 2525);
WIRE 17 -1 (-6125 3775)(-6125 3725);
WIRE 17 -1 (-6125 3825)(-6125 3775);
WIRE 17 -1 (-6125 3875)(-6125 3825);
WIRE 17 -1 (-6125 3925)(-6125 3875);
WIRE 17 -1 (-6125 3975)(-6125 3925);
WIRE 17 -1 (-6125 4025)(-6125 3975);
WIRE 17 -1 (-6125 4050)(-6125 4025);
WIRE 17 -1 (-6125 4050)(-5550 4050);
FORCEPROP 2 LAST SIG_NAME M_E_CPU1_SB_DQ<31:0>
J 0
(-6060 4060);
DISPLAY 0.489362 (-6060 4060);
WIRE 17 -1 (-6125 4625)(-6125 4575);
WIRE 17 -1 (-6125 4675)(-6125 4625);
WIRE 17 -1 (-6125 4575)(-6125 4525);
WIRE 17 -1 (-6125 4525)(-6125 4475);
WIRE 17 -1 (-6125 4725)(-6125 4675);
WIRE 17 -1 (-6125 4725)(-6125 4775);
WIRE 17 -1 (-6125 4475)(-6125 4425);
WIRE 17 -1 (-6125 4425)(-6125 4375);
WIRE 17 -1 (-6125 4775)(-6125 4825);
WIRE 17 -1 (-6125 4825)(-6125 4875);
WIRE 17 -1 (-6125 4375)(-6125 4325);
WIRE 17 -1 (-6125 4275)(-6125 4325);
WIRE 17 -1 (-6125 4875)(-6125 4925);
WIRE 17 -1 (-6125 4975)(-6125 4925);
WIRE 17 -1 (-6125 4225)(-6125 4275);
WIRE 17 -1 (-6125 4175)(-6125 4225);
WIRE 17 -1 (-6125 5025)(-6125 4975);
WIRE 17 -1 (-6125 5075)(-6125 5025);
WIRE 17 -1 (-6125 4125)(-6125 4175);
WIRE 17 -1 (-6125 5125)(-6125 5075);
WIRE 17 -1 (-6125 5175)(-6125 5125);
WIRE 17 -1 (-6125 5225)(-6125 5175);
WIRE 17 -1 (-6125 5275)(-6125 5225);
WIRE 17 -1 (-6125 5325)(-6125 5275);
WIRE 17 -1 (-6125 5375)(-6125 5325);
WIRE 17 -1 (-6125 5425)(-6125 5375);
WIRE 17 -1 (-6125 5475)(-6125 5425);
WIRE 17 -1 (-6125 5525)(-6125 5475);
WIRE 17 -1 (-6125 5575)(-6125 5525);
WIRE 17 -1 (-6125 5625)(-6125 5575);
WIRE 17 -1 (-6125 5675)(-6125 5625);
WIRE 17 -1 (-6125 5700)(-6125 5675);
WIRE 17 -1 (-6125 5700)(-5550 5700);
FORCEPROP 2 LAST SIG_NAME M_E_CPU1_SA_DQ<31:0>
J 0
(-6060 5710);
DISPLAY 0.489362 (-6060 5710);
WIRE 17 -1 (-3425 3775)(-3425 3750);
WIRE 17 -1 (-3425 3775)(-2525 3775);
FORCEPROP 2 LAST SIG_NAME M_E_CPU1_SB_DQS_DP<9:0>
J 0
(-3160 3785);
DISPLAY 0.489362 (-3160 3785);
WIRE 17 -1 (-3225 3725)(-3225 3700);
WIRE 17 -1 (-3225 3725)(-2525 3725);
FORCEPROP 2 LAST SIG_NAME M_E_CPU1_SB_DQS_DN<9:0>
J 0
(-3160 3735);
DISPLAY 0.489362 (-3160 3735);
WIRE 17 -1 (-3425 4825)(-3425 4800);
WIRE 17 -1 (-3425 4825)(-2525 4825);
FORCEPROP 2 LAST SIG_NAME M_E_CPU1_SA_DQS_DP<9:0>
J 0
(-3160 4835);
DISPLAY 0.489362 (-3160 4835);
WIRE 17 -1 (-3225 4775)(-3225 4750);
WIRE 17 -1 (-3225 4775)(-2525 4775);
FORCEPROP 2 LAST SIG_NAME M_E_CPU1_SA_DQS_DN<9:0>
J 0
(-3160 4785);
DISPLAY 0.489362 (-3160 4785);
WIRE 17 -1 (-3425 4800)(-3425 4700);
WIRE 17 -1 (-3425 4700)(-3425 4600);
WIRE 17 -1 (-3425 4600)(-3425 4500);
WIRE 17 -1 (-3225 4750)(-3225 4650);
WIRE 17 -1 (-3225 4650)(-3225 4550);
WIRE 17 -1 (-3225 4550)(-3225 4450);
WIRE 17 -1 (-3225 3600)(-3225 3500);
WIRE 17 -1 (-3225 3700)(-3225 3600);
WIRE 17 -1 (-3225 3500)(-3225 3400);
WIRE 17 -1 (-3225 3400)(-3225 3300);
WIRE 17 -1 (-3425 4500)(-3425 4400);
WIRE 17 -1 (-3425 3550)(-3425 3450);
WIRE 17 -1 (-3425 3650)(-3425 3550);
WIRE 17 -1 (-3425 3450)(-3425 3350);
WIRE 17 -1 (-3425 3250)(-3425 3350);
WIRE 17 -1 (-3425 3750)(-3425 3650);
WIRE 17 -1 (-3425 3150)(-3425 3250);
WIRE 17 -1 (-3425 3050)(-3425 3150);
WIRE 17 -1 (-3225 3200)(-3225 3300);
WIRE 17 -1 (-3225 3100)(-3225 3200);
WIRE 17 -1 (-3225 3000)(-3225 3100);
WIRE 17 -1 (-3225 4450)(-3225 4350);
WIRE 17 -1 (-3225 4250)(-3225 4350);
WIRE 17 -1 (-3225 4150)(-3225 4250);
WIRE 17 -1 (-3225 4050)(-3225 4150);
WIRE 17 -1 (-3425 3050)(-3425 2950);
WIRE 17 -1 (-3225 3000)(-3225 2900);
WIRE 17 -1 (-3425 4300)(-3425 4400);
WIRE 17 -1 (-3425 4200)(-3425 4300);
WIRE 17 -1 (-3425 4100)(-3425 4200);
WIRE 17 -1 (-3425 4100)(-3425 4000);
WIRE 17 -1 (-3225 4050)(-3225 3950);
WIRE 17 -1 (-3425 2950)(-3425 2850);
WIRE 17 -1 (-3225 2900)(-3225 2800);
WIRE 17 -1 (-3425 4000)(-3425 3900);
WIRE 17 -1 (-3225 3950)(-3225 3850);
WIRE 17 -1 (-7925 3925)(-7925 3975);
WIRE 17 -1 (-7925 3975)(-7925 4025);
WIRE 17 -1 (-7925 4025)(-7925 4075);
WIRE 17 -1 (-7925 4075)(-7925 4125);
WIRE 17 -1 (-7925 4175)(-7925 4125);
WIRE 17 -1 (-7925 4175)(-7925 4225);
WIRE 17 -1 (-7925 4275)(-7925 4225);
WIRE 17 -1 (-7925 4275)(-7925 4300);
WIRE 17 -1 (-7925 4300)(-8425 4300);
FORCEPROP 2 LAST SIG_NAME M_E_CPU1_SA_CB<7:0>
J 0
(-8375 4310);
DISPLAY 0.489362 (-8375 4310);
WIRE 17 -1 (-7925 5275)(-7925 5300);
WIRE 17 -1 (-7925 5225)(-7925 5275);
WIRE 17 -1 (-7925 5300)(-8425 5300);
FORCEPROP 2 LAST SIG_NAME M_E_CPU1_SB_CA<6:0>
J 0
(-8410 5310);
DISPLAY 0.489362 (-8410 5310);
WIRE 17 -1 (-7925 5675)(-7925 5700);
WIRE 17 -1 (-7925 5625)(-7925 5675);
WIRE 17 -1 (-7925 5700)(-8425 5700);
FORCEPROP 2 LAST SIG_NAME M_E_CPU1_SA_CA<6:0>
J 0
(-8410 5710);
DISPLAY 0.489362 (-8410 5710);
WIRE 17 -1 (-7925 5175)(-7925 5225);
WIRE 17 -1 (-7925 5575)(-7925 5625);
WIRE 17 -1 (-7925 5125)(-7925 5175);
WIRE 17 -1 (-7925 5075)(-7925 5125);
WIRE 17 -1 (-7925 5025)(-7925 5075);
WIRE 17 -1 (-7925 5525)(-7925 5575);
WIRE 17 -1 (-7925 5475)(-7925 5525);
WIRE 17 -1 (-7925 5425)(-7925 5475);
WIRE 17 -1 (-7925 4975)(-7925 5025);
WIRE 17 -1 (-7925 5375)(-7925 5425);
WIRE 16 -1 (-6575 1300)(-6575 1375);
WIRE 16 -1 (-8800 3300)(-8800 3375);
WIRE 16 -1 (-8500 2650)(-8500 2675);
WIRE 16 -1 (-6425 5650)(-6225 5650);
WIRE 16 -1 (-7625 4250)(-7825 4250);
WIRE 16 -1 (-7625 4100)(-7825 4100);
WIRE 16 -1 (-7625 3950)(-7825 3950);
WIRE 16 -1 (-7625 3800)(-7825 3800);
WIRE 16 -1 (-7625 5350)(-7825 5350);
WIRE 16 -1 (-7625 4950)(-7825 4950);
WIRE 16 -1 (-7625 5400)(-7825 5400);
WIRE 16 -1 (-7625 5000)(-7825 5000);
WIRE 16 -1 (-7625 5450)(-7825 5450);
WIRE 16 -1 (-7625 5050)(-7825 5050);
WIRE 16 -1 (-7625 5500)(-7825 5500);
WIRE 16 -1 (-7625 5100)(-7825 5100);
WIRE 16 -1 (-7625 5550)(-7825 5550);
WIRE 16 -1 (-7625 5150)(-7825 5150);
WIRE 16 -1 (-7625 5600)(-7825 5600);
WIRE 16 -1 (-7625 5200)(-7825 5200);
WIRE 16 -1 (-7625 5650)(-7825 5650);
WIRE 16 -1 (-7625 5250)(-7825 5250);
WIRE 16 -1 (-7625 4200)(-7825 4200);
WIRE 16 -1 (-7625 4150)(-7825 4150);
WIRE 16 -1 (-7625 4050)(-7825 4050);
WIRE 16 -1 (-7625 4000)(-7825 4000);
WIRE 16 -1 (-7625 3900)(-7825 3900);
WIRE 16 -1 (-7625 3750)(-7825 3750);
WIRE 16 -1 (-7625 3700)(-7825 3700);
WIRE 16 -1 (-7625 3650)(-7825 3650);
WIRE 16 -1 (-7625 4350)(-8425 4350);
FORCEPROP 2 LAST SIG_NAME M_E_CPU1_CLK_DN<0>
J 0
(-8375 4360);
DISPLAY 0.489362 (-8375 4360);
WIRE 16 -1 (-7625 4650)(-8425 4650);
FORCEPROP 2 LAST SIG_NAME M_E_CPU1_SA_CS_N<0>
J 0
(-8375 4660);
DISPLAY 0.489362 (-8375 4660);
WIRE 16 -1 (-7625 4700)(-8425 4700);
FORCEPROP 2 LAST SIG_NAME M_E_CPU1_SA_CS_N<1>
J 0
(-8375 4710);
DISPLAY 0.489362 (-8375 4710);
WIRE 16 -1 (-7625 4550)(-8425 4550);
FORCEPROP 2 LAST SIG_NAME M_E_CPU1_SB_CS_N<1>
J 0
(-8375 4560);
DISPLAY 0.489362 (-8375 4560);
WIRE 16 -1 (-6225 5600)(-6425 5600);
WIRE 16 -1 (-6225 5550)(-6425 5550);
WIRE 16 -1 (-6225 5500)(-6425 5500);
WIRE 16 -1 (-6425 5450)(-6225 5450);
WIRE 16 -1 (-6225 5400)(-6425 5400);
WIRE 16 -1 (-6225 5350)(-6425 5350);
WIRE 16 -1 (-6225 5300)(-6425 5300);
WIRE 16 -1 (-6425 5250)(-6225 5250);
WIRE 16 -1 (-6225 5200)(-6425 5200);
WIRE 16 -1 (-6225 5150)(-6425 5150);
WIRE 16 -1 (-6225 5100)(-6425 5100);
WIRE 16 -1 (-6425 5050)(-6225 5050);
WIRE 16 -1 (-6225 5000)(-6425 5000);
WIRE 16 -1 (-6225 4950)(-6425 4950);
WIRE 16 -1 (-6225 4900)(-6425 4900);
WIRE 16 -1 (-6425 4850)(-6225 4850);
WIRE 16 -1 (-6225 4800)(-6425 4800);
WIRE 16 -1 (-6225 4750)(-6425 4750);
WIRE 16 -1 (-6225 4700)(-6425 4700);
WIRE 16 -1 (-6425 4650)(-6225 4650);
WIRE 16 -1 (-6225 4600)(-6425 4600);
WIRE 16 -1 (-6225 4500)(-6425 4500);
WIRE 16 -1 (-6425 4450)(-6225 4450);
WIRE 16 -1 (-6225 4400)(-6425 4400);
WIRE 16 -1 (-6225 4350)(-6425 4350);
WIRE 16 -1 (-6225 4300)(-6425 4300);
WIRE 16 -1 (-6425 4250)(-6225 4250);
WIRE 16 -1 (-6225 4200)(-6425 4200);
WIRE 16 -1 (-6225 4150)(-6425 4150);
WIRE 16 -1 (-6225 4100)(-6425 4100);
WIRE 16 -1 (-6425 4000)(-6225 4000);
WIRE 16 -1 (-6225 3950)(-6425 3950);
WIRE 16 -1 (-6225 3900)(-6425 3900);
WIRE 16 -1 (-6225 3850)(-6425 3850);
WIRE 16 -1 (-6425 3800)(-6225 3800);
WIRE 16 -1 (-6225 3750)(-6425 3750);
WIRE 16 -1 (-6225 3700)(-6425 3700);
WIRE 16 -1 (-6225 3650)(-6425 3650);
WIRE 16 -1 (-6425 3600)(-6225 3600);
WIRE 16 -1 (-6225 3550)(-6425 3550);
WIRE 16 -1 (-6225 3500)(-6425 3500);
WIRE 16 -1 (-6225 3450)(-6425 3450);
WIRE 16 -1 (-6425 3400)(-6225 3400);
WIRE 16 -1 (-6225 3350)(-6425 3350);
WIRE 16 -1 (-6225 3300)(-6425 3300);
WIRE 16 -1 (-6225 3250)(-6425 3250);
WIRE 16 -1 (-6425 3200)(-6225 3200);
WIRE 16 -1 (-6225 3150)(-6425 3150);
WIRE 16 -1 (-6225 3050)(-6425 3050);
WIRE 16 -1 (-6425 3000)(-6225 3000);
WIRE 16 -1 (-6225 2950)(-6425 2950);
WIRE 16 -1 (-6225 2900)(-6425 2900);
WIRE 16 -1 (-6225 2850)(-6425 2850);
WIRE 16 -1 (-6425 2800)(-6225 2800);
WIRE 16 -1 (-6225 2750)(-6425 2750);
WIRE 16 -1 (-6225 2700)(-6425 2700);
WIRE 16 -1 (-6225 2650)(-6425 2650);
WIRE 16 -1 (-6425 2600)(-6225 2600);
WIRE 16 -1 (-6225 2550)(-6425 2550);
WIRE 16 -1 (-6225 2500)(-6425 2500);
WIRE 16 -1 (-6225 2450)(-6425 2450);
WIRE 16 -1 (-7625 2200)(-8425 2200);
FORCEPROP 2 LAST SIG_NAME M_E_CPU1_SB_RSP<0>
J 0
(-8375 2210);
DISPLAY 0.489362 (-8375 2210);
WIRE 16 -1 (-7625 4850)(-8425 4850);
FORCEPROP 2 LAST SIG_NAME M_E_CPU1_SA_PAR
J 0
(-8375 4860);
DISPLAY 0.489362 (-8375 4860);
WIRE 16 -1 (-7625 4800)(-8425 4800);
FORCEPROP 2 LAST SIG_NAME M_E_CPU1_SB_PAR
J 0
(-8375 4810);
DISPLAY 0.489362 (-8375 4810);
WIRE 16 -1 (-3675 4525)(-3325 4525);
WIRE 16 -1 (-3525 4475)(-3675 4475);
WIRE 16 -1 (-3525 3625)(-3675 3625);
WIRE 16 -1 (-3675 3575)(-3325 3575);
WIRE 16 -1 (-3525 3525)(-3675 3525);
WIRE 16 -1 (-3675 3825)(-3325 3825);
WIRE 16 -1 (-3525 3875)(-3675 3875);
WIRE 16 -1 (-3675 2775)(-3325 2775);
WIRE 16 -1 (-3525 2825)(-3675 2825);
WIRE 16 -1 (-3675 3925)(-3325 3925);
WIRE 16 -1 (-3675 3975)(-3525 3975);
WIRE 16 -1 (-3675 2875)(-3325 2875);
WIRE 16 -1 (-3675 2925)(-3525 2925);
WIRE 16 -1 (-3675 4025)(-3325 4025);
WIRE 16 -1 (-3525 4075)(-3675 4075);
WIRE 16 -1 (-3675 2975)(-3325 2975);
WIRE 16 -1 (-3525 3025)(-3675 3025);
WIRE 16 -1 (-3675 4125)(-3325 4125);
WIRE 16 -1 (-3525 4175)(-3675 4175);
WIRE 16 -1 (-3675 3075)(-3325 3075);
WIRE 16 -1 (-3525 3125)(-3675 3125);
WIRE 16 -1 (-3675 4225)(-3325 4225);
WIRE 16 -1 (-3525 4275)(-3675 4275);
WIRE 16 -1 (-3675 3175)(-3325 3175);
WIRE 16 -1 (-3525 3225)(-3675 3225);
WIRE 16 -1 (-3675 4325)(-3325 4325);
WIRE 16 -1 (-3675 4375)(-3525 4375);
WIRE 16 -1 (-3675 3275)(-3325 3275);
WIRE 16 -1 (-3675 3325)(-3525 3325);
WIRE 16 -1 (-3675 4425)(-3325 4425);
WIRE 16 -1 (-3675 3375)(-3325 3375);
WIRE 16 -1 (-3525 3425)(-3675 3425);
WIRE 16 -1 (-3525 4575)(-3675 4575);
WIRE 16 -1 (-3675 3475)(-3325 3475);
WIRE 16 -1 (-3675 4625)(-3325 4625);
WIRE 16 -1 (-3525 4675)(-3675 4675);
WIRE 16 -1 (-3675 4725)(-3325 4725);
WIRE 16 -1 (-3675 4775)(-3525 4775);
WIRE 16 -1 (-3675 3675)(-3325 3675);
WIRE 16 -1 (-3675 3725)(-3525 3725);
WIRE 16 -1 (-7625 2250)(-8425 2250);
FORCEPROP 2 LAST SIG_NAME M_E_CPU1_SA_RSP<0>
J 0
(-8375 2260);
DISPLAY 0.489362 (-8375 2260);
WIRE 16 -1 (-6575 1650)(-6575 1575);
WIRE 16 -1 (-6575 1650)(-7300 1650);
FORCEPROP 2 LAST SIG_NAME PD_CHE_CPU1_DIMM_SAA
J 0
(-7285 1660);
DISPLAY 0.489362 (-7285 1660);
WIRE 16 -1 (-6225 4550)(-6425 4550);
WIRE 16 -1 (-6225 3100)(-6425 3100);
WIRE 16 -1 (-9075 2400)(-8725 2400);
FORCEPROP 2 LAST SIG_NAME PWRGD_CHAF_CPU1
J 0
(-9085 2410);
DISPLAY 0.489362 (-9085 2410);
WIRE 16 -1 (-7625 4500)(-8425 4500);
FORCEPROP 2 LAST SIG_NAME M_E_CPU1_SB_CS_N<0>
J 0
(-8375 4510);
DISPLAY 0.489362 (-8375 4510);
WIRE 16 -1 (-7625 4400)(-8425 4400);
FORCEPROP 2 LAST SIG_NAME M_E_CPU1_CLK_DP<0>
J 0
(-8375 4410);
DISPLAY 0.489362 (-8375 4410);
WIRE 16 -1 (-7625 3600)(-7825 3600);
WIRE 16 -1 (-7625 3550)(-7825 3550);
WIRE 16 -1 (-7625 3500)(-7825 3500);
WIRE 16 -1 (-7625 3450)(-7825 3450);
WIRE 16 -1 (-7625 3300)(-8300 3300);
FORCEPROP 2 LAST SIG_NAME M_E_CPU1_ALERT_N
J 0
(-8285 3310);
DISPLAY 0.489362 (-8285 3310);
WIRE 16 -1 (-7625 3350)(-8300 3350);
FORCEPROP 2 LAST SIG_NAME M_E_CPU1_RESET_N
J 0
(-8285 3360);
DISPLAY 0.489362 (-8285 3360);
WIRE 16 -1 (-7625 3150)(-8625 3150);
FORCEPROP 2 LAST SIG_NAME PD_CHE_CPU1_DIMM_SAA
J 0
(-8600 3160);
DISPLAY 0.489362 (-8600 3160);
WIRE 16 -1 (-2300 6375)(-2300 6275);
WIRE 16 -1 (-2300 6375)(-2175 6375);
WIRE 16 -1 (-2300 6375)(-2875 6375);
WIRE 16 -1 (-2875 6275)(-2875 6375);
WIRE 16 -1 (-2875 6375)(-2875 6450);
WIRE 16 -1 (-2175 5650)(-2175 6375);
WIRE 16 -1 (-1875 5650)(-2175 5650);
WIRE 16 -1 (-2175 5600)(-2175 5650);
WIRE 16 -1 (-1875 5600)(-2175 5600);
WIRE 16 -1 (-2175 5600)(-2175 5550);
WIRE 16 -1 (-2175 5550)(-1875 5550);
WIRE 16 -1 (-2300 5950)(-2300 6075);
WIRE 16 -1 (-2300 5950)(-2875 5950);
WIRE 16 -1 (-2875 5950)(-2875 6075);
WIRE 16 -1 (-2875 5950)(-2875 5875);
WIRE 16 -1 (-375 2500)(-375 2400);
WIRE 16 -1 (-375 2550)(-375 2500);
WIRE 16 -1 (-375 2500)(-675 2500);
WIRE 16 -1 (-375 2400)(-375 2350);
WIRE 16 -1 (-375 2400)(-675 2400);
WIRE 16 -1 (-375 2350)(-375 2300);
WIRE 16 -1 (-375 2350)(-675 2350);
WIRE 16 -1 (-375 2600)(-375 2550);
WIRE 16 -1 (-375 2550)(-675 2550);
WIRE 16 -1 (-375 2650)(-375 2600);
WIRE 16 -1 (-375 2600)(-675 2600);
WIRE 16 -1 (-375 2300)(-375 2125);
WIRE 16 -1 (-375 2300)(-675 2300);
WIRE 16 -1 (-375 2700)(-375 2650);
WIRE 16 -1 (-375 2650)(-675 2650);
WIRE 16 -1 (-375 2750)(-375 2700);
WIRE 16 -1 (-375 2700)(-675 2700);
WIRE 16 -1 (-375 2800)(-375 2750);
WIRE 16 -1 (-375 2750)(-675 2750);
WIRE 16 -1 (-375 2850)(-375 2800);
WIRE 16 -1 (-375 2800)(-675 2800);
WIRE 16 -1 (-375 2900)(-375 2850);
WIRE 16 -1 (-375 2850)(-675 2850);
WIRE 16 -1 (-375 2950)(-375 2900);
WIRE 16 -1 (-375 2900)(-675 2900);
WIRE 16 -1 (-375 3000)(-375 2950);
WIRE 16 -1 (-375 2950)(-675 2950);
WIRE 16 -1 (-375 3050)(-375 3000);
WIRE 16 -1 (-375 3000)(-675 3000);
WIRE 16 -1 (-375 3100)(-375 3050);
WIRE 16 -1 (-375 3050)(-675 3050);
WIRE 16 -1 (-375 3150)(-375 3100);
WIRE 16 -1 (-375 3100)(-675 3100);
WIRE 16 -1 (-375 3200)(-375 3150);
WIRE 16 -1 (-375 3150)(-675 3150);
WIRE 16 -1 (-375 3250)(-375 3200);
WIRE 16 -1 (-375 3200)(-675 3200);
WIRE 16 -1 (-375 3300)(-375 3250);
WIRE 16 -1 (-375 3250)(-675 3250);
WIRE 16 -1 (-375 3350)(-375 3300);
WIRE 16 -1 (-375 3300)(-675 3300);
WIRE 16 -1 (-375 3400)(-375 3350);
WIRE 16 -1 (-375 3350)(-675 3350);
WIRE 16 -1 (-375 3450)(-375 3400);
WIRE 16 -1 (-375 3400)(-675 3400);
WIRE 16 -1 (-375 3500)(-375 3450);
WIRE 16 -1 (-375 3450)(-675 3450);
WIRE 16 -1 (-375 3550)(-375 3500);
WIRE 16 -1 (-375 3500)(-675 3500);
WIRE 16 -1 (-375 3600)(-375 3550);
WIRE 16 -1 (-375 3550)(-675 3550);
WIRE 16 -1 (-375 3650)(-375 3600);
WIRE 16 -1 (-375 3600)(-675 3600);
WIRE 16 -1 (-375 3700)(-375 3650);
WIRE 16 -1 (-375 3650)(-675 3650);
WIRE 16 -1 (-375 3750)(-375 3700);
WIRE 16 -1 (-375 3700)(-675 3700);
WIRE 16 -1 (-375 3800)(-375 3750);
WIRE 16 -1 (-375 3750)(-675 3750);
WIRE 16 -1 (-375 3850)(-375 3800);
WIRE 16 -1 (-375 3800)(-675 3800);
WIRE 16 -1 (-375 3900)(-375 3850);
WIRE 16 -1 (-375 3850)(-675 3850);
WIRE 16 -1 (-375 3950)(-375 3900);
WIRE 16 -1 (-375 3900)(-675 3900);
WIRE 16 -1 (-375 4000)(-375 3950);
WIRE 16 -1 (-375 3950)(-675 3950);
WIRE 16 -1 (-375 4050)(-375 4000);
WIRE 16 -1 (-375 4000)(-675 4000);
WIRE 16 -1 (-375 4100)(-375 4050);
WIRE 16 -1 (-375 4050)(-675 4050);
WIRE 16 -1 (-375 4150)(-375 4100);
WIRE 16 -1 (-375 4100)(-675 4100);
WIRE 16 -1 (-375 4200)(-375 4150);
WIRE 16 -1 (-375 4150)(-675 4150);
WIRE 16 -1 (-375 4250)(-375 4200);
WIRE 16 -1 (-375 4200)(-675 4200);
WIRE 16 -1 (-375 4300)(-375 4250);
WIRE 16 -1 (-375 4250)(-675 4250);
WIRE 16 -1 (-375 4350)(-375 4300);
WIRE 16 -1 (-375 4300)(-675 4300);
WIRE 16 -1 (-375 4400)(-375 4350);
WIRE 16 -1 (-375 4350)(-675 4350);
WIRE 16 -1 (-375 4450)(-375 4400);
WIRE 16 -1 (-375 4400)(-675 4400);
WIRE 16 -1 (-375 4500)(-375 4450);
WIRE 16 -1 (-375 4450)(-675 4450);
WIRE 16 -1 (-375 4550)(-375 4500);
WIRE 16 -1 (-375 4500)(-675 4500);
WIRE 16 -1 (-375 4600)(-375 4550);
WIRE 16 -1 (-375 4550)(-675 4550);
WIRE 16 -1 (-375 4650)(-375 4600);
WIRE 16 -1 (-375 4600)(-675 4600);
WIRE 16 -1 (-375 4700)(-375 4650);
WIRE 16 -1 (-375 4650)(-675 4650);
WIRE 16 -1 (-375 4750)(-375 4700);
WIRE 16 -1 (-375 4700)(-675 4700);
WIRE 16 -1 (-375 4800)(-375 4750);
WIRE 16 -1 (-375 4750)(-675 4750);
WIRE 16 -1 (-375 4850)(-375 4800);
WIRE 16 -1 (-375 4800)(-675 4800);
WIRE 16 -1 (-375 4900)(-375 4850);
WIRE 16 -1 (-375 4850)(-675 4850);
WIRE 16 -1 (-375 4950)(-375 4900);
WIRE 16 -1 (-375 4900)(-675 4900);
WIRE 16 -1 (-375 5000)(-375 4950);
WIRE 16 -1 (-375 4950)(-675 4950);
WIRE 16 -1 (-375 5050)(-375 5000);
WIRE 16 -1 (-375 5000)(-675 5000);
WIRE 16 -1 (-375 5100)(-375 5050);
WIRE 16 -1 (-375 5050)(-675 5050);
WIRE 16 -1 (-375 5150)(-375 5100);
WIRE 16 -1 (-375 5100)(-675 5100);
WIRE 16 -1 (-375 5200)(-375 5150);
WIRE 16 -1 (-375 5150)(-675 5150);
WIRE 16 -1 (-375 5250)(-375 5200);
WIRE 16 -1 (-375 5200)(-675 5200);
WIRE 16 -1 (-375 5300)(-375 5250);
WIRE 16 -1 (-375 5250)(-675 5250);
WIRE 16 -1 (-375 5350)(-375 5300);
WIRE 16 -1 (-375 5300)(-675 5300);
WIRE 16 -1 (-375 5400)(-375 5350);
WIRE 16 -1 (-375 5350)(-675 5350);
WIRE 16 -1 (-375 5450)(-375 5400);
WIRE 16 -1 (-375 5400)(-675 5400);
WIRE 16 -1 (-375 5500)(-375 5450);
WIRE 16 -1 (-375 5450)(-675 5450);
WIRE 16 -1 (-375 5550)(-375 5500);
WIRE 16 -1 (-375 5500)(-675 5500);
WIRE 16 -1 (-375 5600)(-375 5550);
WIRE 16 -1 (-375 5550)(-675 5550);
WIRE 16 -1 (-375 5650)(-375 5600);
WIRE 16 -1 (-375 5600)(-675 5600);
WIRE 16 -1 (-375 5650)(-675 5650);
WIRE 16 -1 (-1875 2450)(-2175 2450);
WIRE 16 -1 (-2175 2500)(-2175 2450);
WIRE 16 -1 (-2175 2450)(-2175 2400);
WIRE 16 -1 (-1875 2400)(-2175 2400);
WIRE 16 -1 (-2175 2400)(-2175 2300);
WIRE 16 -1 (-1875 2500)(-2175 2500);
WIRE 16 -1 (-2175 2550)(-2175 2500);
WIRE 16 -1 (-1875 2550)(-2175 2550);
WIRE 16 -1 (-2175 2600)(-2175 2550);
WIRE 16 -1 (-1875 2600)(-2175 2600);
WIRE 16 -1 (-2175 2650)(-2175 2600);
WIRE 16 -1 (-1875 2650)(-2175 2650);
WIRE 16 -1 (-2175 2700)(-2175 2650);
WIRE 16 -1 (-1875 2700)(-2175 2700);
WIRE 16 -1 (-2175 2750)(-2175 2700);
WIRE 16 -1 (-1875 2750)(-2175 2750);
WIRE 16 -1 (-2175 2800)(-2175 2750);
WIRE 16 -1 (-1875 2800)(-2175 2800);
WIRE 16 -1 (-2175 2850)(-2175 2800);
WIRE 16 -1 (-1875 2850)(-2175 2850);
WIRE 16 -1 (-2175 2900)(-2175 2850);
WIRE 16 -1 (-1875 2900)(-2175 2900);
WIRE 16 -1 (-2175 2950)(-2175 2900);
WIRE 16 -1 (-1875 2950)(-2175 2950);
WIRE 16 -1 (-2175 3000)(-2175 2950);
WIRE 16 -1 (-1875 3000)(-2175 3000);
WIRE 16 -1 (-2175 3050)(-2175 3000);
WIRE 16 -1 (-1875 3050)(-2175 3050);
WIRE 16 -1 (-2175 3100)(-2175 3050);
WIRE 16 -1 (-1875 3100)(-2175 3100);
WIRE 16 -1 (-2175 3150)(-2175 3100);
WIRE 16 -1 (-1875 3150)(-2175 3150);
WIRE 16 -1 (-2175 3200)(-2175 3150);
WIRE 16 -1 (-1875 3200)(-2175 3200);
WIRE 16 -1 (-2175 3250)(-2175 3200);
WIRE 16 -1 (-1875 3250)(-2175 3250);
WIRE 16 -1 (-2175 3300)(-2175 3250);
WIRE 16 -1 (-1875 3300)(-2175 3300);
WIRE 16 -1 (-2175 3350)(-2175 3300);
WIRE 16 -1 (-1875 3350)(-2175 3350);
WIRE 16 -1 (-2175 3400)(-2175 3350);
WIRE 16 -1 (-1875 3400)(-2175 3400);
WIRE 16 -1 (-2175 3450)(-2175 3400);
WIRE 16 -1 (-1875 3450)(-2175 3450);
WIRE 16 -1 (-2175 3500)(-2175 3450);
WIRE 16 -1 (-1875 3500)(-2175 3500);
WIRE 16 -1 (-2175 3550)(-2175 3500);
WIRE 16 -1 (-1875 3550)(-2175 3550);
WIRE 16 -1 (-2175 3600)(-2175 3550);
WIRE 16 -1 (-1875 3600)(-2175 3600);
WIRE 16 -1 (-2175 3650)(-2175 3600);
WIRE 16 -1 (-1875 3650)(-2175 3650);
WIRE 16 -1 (-2175 3700)(-2175 3650);
WIRE 16 -1 (-1875 3700)(-2175 3700);
WIRE 16 -1 (-2175 3750)(-2175 3700);
WIRE 16 -1 (-1875 3750)(-2175 3750);
WIRE 16 -1 (-2175 3800)(-2175 3750);
WIRE 16 -1 (-1875 3800)(-2175 3800);
WIRE 16 -1 (-2175 3850)(-2175 3800);
WIRE 16 -1 (-1875 3850)(-2175 3850);
WIRE 16 -1 (-2175 3900)(-2175 3850);
WIRE 16 -1 (-1875 3900)(-2175 3900);
WIRE 16 -1 (-2175 3950)(-2175 3900);
WIRE 16 -1 (-1875 3950)(-2175 3950);
WIRE 16 -1 (-2175 4000)(-2175 3950);
WIRE 16 -1 (-1875 4000)(-2175 4000);
WIRE 16 -1 (-2175 4050)(-2175 4000);
WIRE 16 -1 (-2175 4100)(-2175 4050);
WIRE 16 -1 (-1875 4050)(-2175 4050);
WIRE 16 -1 (-1875 4100)(-2175 4100);
WIRE 16 -1 (-2175 4150)(-2175 4100);
WIRE 16 -1 (-1875 4150)(-2175 4150);
WIRE 16 -1 (-2175 4200)(-2175 4150);
WIRE 16 -1 (-1875 4200)(-2175 4200);
WIRE 16 -1 (-2175 4250)(-2175 4200);
WIRE 16 -1 (-1875 4250)(-2175 4250);
WIRE 16 -1 (-2175 4300)(-2175 4250);
WIRE 16 -1 (-1875 4300)(-2175 4300);
WIRE 16 -1 (-2175 4350)(-2175 4300);
WIRE 16 -1 (-1875 4350)(-2175 4350);
WIRE 16 -1 (-2175 4400)(-2175 4350);
WIRE 16 -1 (-1875 4400)(-2175 4400);
WIRE 16 -1 (-2175 4450)(-2175 4400);
WIRE 16 -1 (-1875 4450)(-2175 4450);
WIRE 16 -1 (-2175 4500)(-2175 4450);
WIRE 16 -1 (-1875 4500)(-2175 4500);
WIRE 16 -1 (-2175 4550)(-2175 4500);
WIRE 16 -1 (-1875 4550)(-2175 4550);
WIRE 16 -1 (-2175 4600)(-2175 4550);
WIRE 16 -1 (-1875 4600)(-2175 4600);
WIRE 16 -1 (-2175 4650)(-2175 4600);
WIRE 16 -1 (-1875 4650)(-2175 4650);
WIRE 16 -1 (-2175 4700)(-2175 4650);
WIRE 16 -1 (-1875 4700)(-2175 4700);
WIRE 16 -1 (-2175 4750)(-2175 4700);
WIRE 16 -1 (-1875 4750)(-2175 4750);
WIRE 16 -1 (-2175 4800)(-2175 4750);
WIRE 16 -1 (-1875 4800)(-2175 4800);
WIRE 16 -1 (-2175 4850)(-2175 4800);
WIRE 16 -1 (-1875 4850)(-2175 4850);
WIRE 16 -1 (-2175 4900)(-2175 4850);
WIRE 16 -1 (-1875 4900)(-2175 4900);
WIRE 16 -1 (-2175 4950)(-2175 4900);
WIRE 16 -1 (-1875 4950)(-2175 4950);
WIRE 16 -1 (-2175 5000)(-2175 4950);
WIRE 16 -1 (-1875 5000)(-2175 5000);
WIRE 16 -1 (-2175 5050)(-2175 5000);
WIRE 16 -1 (-1875 5050)(-2175 5050);
WIRE 16 -1 (-2175 5100)(-2175 5050);
WIRE 16 -1 (-1875 5100)(-2175 5100);
WIRE 16 -1 (-2175 5150)(-2175 5100);
WIRE 16 -1 (-1875 5150)(-2175 5150);
WIRE 16 -1 (-2175 5200)(-2175 5150);
WIRE 16 -1 (-1875 5200)(-2175 5200);
WIRE 16 -1 (-2175 5250)(-2175 5200);
WIRE 16 -1 (-1875 5250)(-2175 5250);
WIRE 16 -1 (-2175 5300)(-2175 5250);
WIRE 16 -1 (-1875 5300)(-2175 5300);
WIRE 16 -1 (-2175 5350)(-2175 5300);
WIRE 16 -1 (-1875 5350)(-2175 5350);
WIRE 16 -1 (-2175 5400)(-2175 5350);
WIRE 16 -1 (-1875 5400)(-2175 5400);
WIRE 16 -1 (-2175 5450)(-2175 5400);
WIRE 16 -1 (-1875 5450)(-2175 5450);
WIRE 16 -1 (-2175 5500)(-2175 5450);
WIRE 16 -1 (-1875 5500)(-2175 5500);
WIRE 16 -1 (-8800 3575)(-8800 3600);
WIRE 16 -1 (-8800 3600)(-8700 3600);
WIRE 16 -1 (-8700 3625)(-8700 3600);
WIRE 16 -1 (-8700 3600)(-8700 3200);
WIRE 16 -1 (-8700 3200)(-7625 3200);
WIRE 16 -1 (-8300 2400)(-8300 2800);
WIRE 16 -1 (-8300 2400)(-8500 2400);
WIRE 16 -1 (-7625 2800)(-8300 2800);
FORCEPROP 2 LAST SIG_NAME PWRGD_CHE_CPU1_DIMM
J 0
(-8185 2810);
DISPLAY 0.489362 (-8185 2810);
FORCEPROP 2 LASTPROP $XRERR UNIQUE?
J 0
(-8425 2810);
DISPLAY 0.638298 (-8425 2810);
PAINT MONO (-8425 2810);
DISPLAY INVISIBLE (-8425 2810);
WIRE 16 -1 (-8500 2450)(-8500 2400);
WIRE 16 -1 (-8500 2400)(-8525 2400);
WIRE 16 -1 (-7725 2875)(-7825 2875);
WIRE 16 -1 (-7725 3050)(-7725 2875);
WIRE 16 -1 (-7625 3050)(-7725 3050);
FORCEPROP 2 LAST SIG_NAME I3C_SPD_DDRE_CPU1_SCL
J 0
(-8110 3060);
DISPLAY 0.446809 (-8110 3060);
FORCEPROP 2 LASTPROP $XRERR UNIQUE?
J 0
(-8350 3060);
DISPLAY 0.638298 (-8350 3060);
PAINT MONO (-8350 3060);
DISPLAY INVISIBLE (-8350 3060);
WIRE 16 -1 (-7625 3100)(-8200 3100);
FORCEPROP 2 LAST SIG_NAME I3C_SPD_DDRE_CPU1_SDA
J 0
(-8110 3110);
DISPLAY 0.446809 (-8110 3110);
FORCEPROP 2 LASTPROP $XRERR UNIQUE?
J 0
(-8350 3110);
DISPLAY 0.638298 (-8350 3110);
PAINT MONO (-8350 3110);
DISPLAY INVISIBLE (-8350 3110);
WIRE 16 -1 (-8025 2875)(-8525 2875);
FORCEPROP 2 LAST SIG_NAME I3C_SPD_DDRAF_CPU1_SCL
J 0
(-8585 2885);
DISPLAY 0.489362 (-8585 2885);
WIRE 16 -1 (-8425 3100)(-8400 3100);
WIRE 16 -1 (-8425 2975)(-8425 3100);
WIRE 16 -1 (-8425 2975)(-8900 2975);
FORCEPROP 2 LAST SIG_NAME I3C_SPD_DDRAF_CPU1_SDA
J 0
(-8935 2985);
DISPLAY 0.489362 (-8935 2985);
DOT 1 (-2875 6375);
DOT 1 (-2300 6375);
DOT 1 (-2875 5950);
DOT 1 (-8500 2400);
DOT 1 (-8700 3600);
DOT 1 (-2175 5650);
DOT 1 (-2175 2450);
DOT 1 (-2175 2500);
DOT 1 (-2175 2550);
DOT 1 (-2175 2400);
DOT 1 (-2175 2700);
DOT 1 (-2175 2650);
DOT 1 (-2175 2750);
DOT 1 (-2175 2600);
DOT 1 (-2175 2800);
DOT 1 (-2175 3050);
DOT 1 (-2175 2950);
DOT 1 (-2175 2850);
DOT 1 (-2175 2900);
DOT 1 (-2175 3000);
DOT 1 (-2175 3200);
DOT 1 (-2175 3300);
DOT 1 (-2175 3150);
DOT 1 (-2175 3100);
DOT 1 (-2175 3250);
DOT 1 (-2175 3550);
DOT 1 (-2175 3450);
DOT 1 (-2175 3400);
DOT 1 (-2175 3350);
DOT 1 (-2175 3500);
DOT 1 (-2175 3700);
DOT 1 (-2175 3750);
DOT 1 (-2175 3600);
DOT 1 (-2175 3650);
DOT 1 (-2175 3800);
DOT 1 (-2175 3850);
DOT 1 (-2175 4050);
DOT 1 (-2175 3900);
DOT 1 (-2175 3950);
DOT 1 (-2175 4000);
DOT 1 (-375 2300);
DOT 1 (-375 2550);
DOT 1 (-375 2500);
DOT 1 (-375 2400);
DOT 1 (-375 2350);
DOT 1 (-375 2800);
DOT 1 (-375 2700);
DOT 1 (-375 2600);
DOT 1 (-375 2650);
DOT 1 (-375 2750);
DOT 1 (-375 3000);
DOT 1 (-375 2950);
DOT 1 (-375 2850);
DOT 1 (-375 2900);
DOT 1 (-375 3050);
DOT 1 (-375 3300);
DOT 1 (-375 3200);
DOT 1 (-375 3150);
DOT 1 (-375 3100);
DOT 1 (-375 3250);
DOT 1 (-375 3550);
DOT 1 (-375 3450);
DOT 1 (-375 3400);
DOT 1 (-375 3350);
DOT 1 (-375 3500);
DOT 1 (-375 3750);
DOT 1 (-375 3700);
DOT 1 (-375 3650);
DOT 1 (-375 3600);
DOT 1 (-375 3800);
DOT 1 (-375 3850);
DOT 1 (-375 4050);
DOT 1 (-375 3950);
DOT 1 (-375 3900);
DOT 1 (-375 4000);
DOT 1 (-2175 4100);
DOT 1 (-375 4100);
DOT 1 (-2175 4200);
DOT 1 (-2175 4250);
DOT 1 (-2175 4150);
DOT 1 (-2175 4300);
DOT 1 (-2175 4350);
DOT 1 (-2175 4550);
DOT 1 (-2175 4600);
DOT 1 (-2175 4400);
DOT 1 (-2175 4450);
DOT 1 (-2175 4500);
DOT 1 (-2175 4800);
DOT 1 (-2175 4700);
DOT 1 (-2175 4850);
DOT 1 (-2175 4650);
DOT 1 (-2175 4750);
DOT 1 (-2175 5050);
DOT 1 (-2175 5000);
DOT 1 (-2175 4900);
DOT 1 (-2175 4950);
DOT 1 (-2175 5100);
DOT 1 (-2175 5250);
DOT 1 (-2175 5350);
DOT 1 (-2175 5200);
DOT 1 (-2175 5150);
DOT 1 (-2175 5300);
DOT 1 (-2175 5400);
DOT 1 (-2175 5450);
DOT 1 (-375 4300);
DOT 1 (-375 4200);
DOT 1 (-375 4150);
DOT 1 (-375 4250);
DOT 1 (-375 4350);
DOT 1 (-375 4600);
DOT 1 (-375 4500);
DOT 1 (-375 4450);
DOT 1 (-375 4400);
DOT 1 (-375 4550);
DOT 1 (-375 4800);
DOT 1 (-375 4750);
DOT 1 (-375 4650);
DOT 1 (-375 4700);
DOT 1 (-375 4850);
DOT 1 (-375 5050);
DOT 1 (-375 5000);
DOT 1 (-375 4900);
DOT 1 (-375 4950);
DOT 1 (-375 5100);
DOT 1 (-375 5350);
DOT 1 (-375 5250);
DOT 1 (-375 5200);
DOT 1 (-375 5150);
DOT 1 (-375 5300);
DOT 1 (-375 5600);
DOT 1 (-375 5500);
DOT 1 (-375 5400);
DOT 1 (-375 5450);
DOT 1 (-375 5550);
DOT 1 (-2175 5600);
QUIT
